FILE_TYPE = MACRO_DRAWING;
SET COLOR_WIRE YELLOW;
SET COLOR_PROP MONO;
SET COLOR_DOT WHITE;
SET COLOR_ARC YELLOW;
SET COLOR_BODY GREEN;
SET COLOR_NOTE MONO;
SET PROP_DISPLAY VALUE;
SET PAGE_NUMBER P124;
FORCEADD GND..1
(225 825);
FORCEPROP 3 LASTPIN (225 875) SIG_NAME GND\g
J 0
(235 885);
DISPLAY 0.659574 (235 885);
PAINT MONO (235 885);
DISPLAY INVISIBLE (235 885);
FORCEPROP 1 LAST VOLTAGE 0.0V
J 0
(180 782);
DISPLAY 0.340426 (180 782);
PAINT SKYBLUE (180 782);
DISPLAY INVISIBLE (180 782);
FORCEPROP 2 LAST CDS_LIB mstr_symbols
J 0
(225 825);
PAINT ORANGE (225 825);
DISPLAY INVISIBLE (225 825);
FORCEPROP 1 LAST SIZE 1B
J 0
(300 775);
DISPLAY 1.170213 (300 775);
PAINT AQUA (300 775);
DISPLAY INVISIBLE (300 775);
FORCEPROP 1 LAST BODY_TYPE PLUMBING
J 0
(180 782);
DISPLAY 0.340426 (180 782);
PAINT GREEN (180 782);
DISPLAY INVISIBLE (180 782);
FORCEPROP 1 LAST PATH I13
J 0
(300 825);
DISPLAY 0.872340 (300 825);
PAINT AQUA (300 825);
DISPLAY INVISIBLE (300 825);
FORCEPROP 1 LAST HDL_POWER GND
J 0
(225 975);
DISPLAY 1.170213 (225 975);
PAINT GREEN (225 975);
DISPLAY INVISIBLE (225 975);
FORCEADD GND..1
(2200 4075);
FORCEPROP 3 LASTPIN (2200 4125) SIG_NAME GND\g
J 0
(2210 4135);
DISPLAY 0.659574 (2210 4135);
PAINT MONO (2210 4135);
DISPLAY INVISIBLE (2210 4135);
FORCEPROP 1 LAST VOLTAGE 0.0V
J 0
(2155 4032);
DISPLAY 0.340426 (2155 4032);
PAINT SKYBLUE (2155 4032);
DISPLAY INVISIBLE (2155 4032);
FORCEPROP 1 LAST SIZE 1B
J 0
(2275 4025);
DISPLAY 1.170213 (2275 4025);
PAINT AQUA (2275 4025);
DISPLAY INVISIBLE (2275 4025);
FORCEPROP 2 LAST CDS_LIB mstr_symbols
J 0
(2200 4075);
PAINT ORANGE (2200 4075);
DISPLAY INVISIBLE (2200 4075);
FORCEPROP 1 LAST BODY_TYPE PLUMBING
J 0
(2155 4032);
DISPLAY 0.340426 (2155 4032);
PAINT GREEN (2155 4032);
DISPLAY INVISIBLE (2155 4032);
FORCEPROP 1 LAST PATH I14
J 0
(2275 4075);
DISPLAY 0.872340 (2275 4075);
PAINT AQUA (2275 4075);
DISPLAY INVISIBLE (2275 4075);
FORCEPROP 1 LAST HDL_POWER GND
J 0
(2200 4225);
DISPLAY 1.170213 (2200 4225);
PAINT GREEN (2200 4225);
DISPLAY INVISIBLE (2200 4225);
FORCEADD LBG_CORE_QAT_EXT_D..14
(1200 2700);
FORCEPROP 1 LAST LOCATION U7C1
J 0
(675 4700);
DISPLAY 0.617021 (675 4700);
PAINT AQUA (675 4700);
FORCEPROP 1 LAST PART_NUMBER H91415-002
J 0
(650 750);
DISPLAY 0.617021 (650 750);
PAINT BLUE (650 750);
FORCEPROP 1 LAST MATERIAL IC
J 0
(650 4600);
DISPLAY 0.617021 (650 4600);
PAINT SKYBLUE (650 4600);
FORCEPROP 2 LASTPIN (1800 4200) $PN CA52
J 0
(1810 4210);
DISPLAY 0.617021 (1810 4210);
PAINT ORANGE (1810 4210);
FORCEPROP 2 LASTPIN (1800 4250) $PN CA50
J 0
(1810 4260);
DISPLAY 0.617021 (1810 4260);
PAINT ORANGE (1810 4260);
FORCEPROP 2 LASTPIN (1800 4300) $PN CA26
J 0
(1810 4310);
DISPLAY 0.617021 (1810 4310);
PAINT ORANGE (1810 4310);
FORCEPROP 2 LASTPIN (1800 4350) $PN CA18
J 0
(1810 4360);
DISPLAY 0.617021 (1810 4360);
PAINT ORANGE (1810 4360);
FORCEPROP 2 LASTPIN (1800 4400) $PN CA15
J 0
(1810 4410);
DISPLAY 0.617021 (1810 4410);
PAINT ORANGE (1810 4410);
FORCEPROP 2 LASTPIN (600 950) $PN BY49
J 2
(590 960);
DISPLAY 0.617021 (590 960);
PAINT ORANGE (590 960);
FORCEPROP 2 LASTPIN (600 1000) $PN BY40
J 2
(590 1010);
DISPLAY 0.617021 (590 1010);
PAINT ORANGE (590 1010);
FORCEPROP 2 LASTPIN (600 1100) $PN BW26
J 2
(590 1110);
DISPLAY 0.617021 (590 1110);
PAINT ORANGE (590 1110);
FORCEPROP 2 LASTPIN (600 1150) $PN BW18
J 2
(590 1160);
DISPLAY 0.617021 (590 1160);
PAINT ORANGE (590 1160);
FORCEPROP 2 LASTPIN (600 1200) $PN BW15
J 2
(590 1210);
DISPLAY 0.617021 (590 1210);
PAINT ORANGE (590 1210);
FORCEPROP 2 LASTPIN (600 1250) $PN BV40
J 2
(590 1260);
DISPLAY 0.617021 (590 1260);
PAINT ORANGE (590 1260);
FORCEPROP 2 LASTPIN (600 1350) $PN BU63
J 2
(590 1360);
DISPLAY 0.617021 (590 1360);
PAINT ORANGE (590 1360);
FORCEPROP 2 LASTPIN (600 1400) $PN BU61
J 2
(590 1410);
DISPLAY 0.617021 (590 1410);
PAINT ORANGE (590 1410);
FORCEPROP 2 LASTPIN (600 1450) $PN BU59
J 2
(590 1460);
DISPLAY 0.617021 (590 1460);
PAINT ORANGE (590 1460);
FORCEPROP 2 LASTPIN (600 1500) $PN BU57
J 2
(590 1510);
DISPLAY 0.617021 (590 1510);
PAINT ORANGE (590 1510);
FORCEPROP 2 LASTPIN (600 1550) $PN BU54
J 2
(590 1560);
DISPLAY 0.617021 (590 1560);
PAINT ORANGE (590 1560);
FORCEPROP 2 LASTPIN (600 1600) $PN BU52
J 2
(590 1610);
DISPLAY 0.617021 (590 1610);
PAINT ORANGE (590 1610);
FORCEPROP 2 LASTPIN (600 1650) $PN BU50
J 2
(590 1660);
DISPLAY 0.617021 (590 1660);
PAINT ORANGE (590 1660);
FORCEPROP 2 LASTPIN (600 1700) $PN BU48
J 2
(590 1710);
DISPLAY 0.617021 (590 1710);
PAINT ORANGE (590 1710);
FORCEPROP 2 LASTPIN (600 1750) $PN BU45
J 2
(590 1760);
DISPLAY 0.617021 (590 1760);
PAINT ORANGE (590 1760);
FORCEPROP 2 LASTPIN (600 1800) $PN BU43
J 2
(590 1810);
DISPLAY 0.617021 (590 1810);
PAINT ORANGE (590 1810);
FORCEPROP 2 LASTPIN (600 1850) $PN BU41
J 2
(590 1860);
DISPLAY 0.617021 (590 1860);
PAINT ORANGE (590 1860);
FORCEPROP 2 LASTPIN (600 1900) $PN BU39
J 2
(590 1910);
DISPLAY 0.617021 (590 1910);
PAINT ORANGE (590 1910);
FORCEPROP 2 LASTPIN (600 1950) $PN BU37
J 2
(590 1960);
DISPLAY 0.617021 (590 1960);
PAINT ORANGE (590 1960);
FORCEPROP 2 LASTPIN (600 2000) $PN BU34
J 2
(590 2010);
DISPLAY 0.617021 (590 2010);
PAINT ORANGE (590 2010);
FORCEPROP 2 LASTPIN (600 2050) $PN BU32
J 2
(590 2060);
DISPLAY 0.617021 (590 2060);
PAINT ORANGE (590 2060);
FORCEPROP 2 LASTPIN (600 2100) $PN BU30
J 2
(590 2110);
DISPLAY 0.617021 (590 2110);
PAINT ORANGE (590 2110);
FORCEPROP 2 LASTPIN (600 2150) $PN BU28
J 2
(590 2160);
DISPLAY 0.617021 (590 2160);
PAINT ORANGE (590 2160);
FORCEPROP 2 LASTPIN (600 2200) $PN BU26
J 2
(590 2210);
DISPLAY 0.617021 (590 2210);
PAINT ORANGE (590 2210);
FORCEPROP 2 LASTPIN (600 2250) $PN BU24
J 2
(590 2260);
DISPLAY 0.617021 (590 2260);
PAINT ORANGE (590 2260);
FORCEPROP 2 LASTPIN (600 2300) $PN BU22
J 2
(590 2310);
DISPLAY 0.617021 (590 2310);
PAINT ORANGE (590 2310);
FORCEPROP 2 LASTPIN (600 2350) $PN BU20
J 2
(590 2360);
DISPLAY 0.617021 (590 2360);
PAINT ORANGE (590 2360);
FORCEPROP 2 LASTPIN (600 2400) $PN BU18
J 2
(590 2410);
DISPLAY 0.617021 (590 2410);
PAINT ORANGE (590 2410);
FORCEPROP 2 LASTPIN (600 2450) $PN BU15
J 2
(590 2460);
DISPLAY 0.617021 (590 2460);
PAINT ORANGE (590 2460);
FORCEPROP 2 LASTPIN (600 2500) $PN BV49
J 2
(590 2510);
DISPLAY 0.617021 (590 2510);
PAINT ORANGE (590 2510);
FORCEPROP 2 LASTPIN (600 2550) $PN BU11
J 2
(590 2560);
DISPLAY 0.617021 (590 2560);
PAINT ORANGE (590 2560);
FORCEPROP 2 LASTPIN (600 2600) $PN BU13
J 2
(590 2610);
DISPLAY 0.617021 (590 2610);
PAINT ORANGE (590 2610);
FORCEPROP 2 LASTPIN (600 2650) $PN BT66
J 2
(590 2660);
DISPLAY 0.617021 (590 2660);
PAINT ORANGE (590 2660);
FORCEPROP 2 LASTPIN (600 2700) $PN BR6
J 2
(590 2710);
DISPLAY 0.617021 (590 2710);
PAINT ORANGE (590 2710);
FORCEPROP 2 LASTPIN (600 2750) $PN BR58
J 2
(590 2760);
DISPLAY 0.617021 (590 2760);
PAINT ORANGE (590 2760);
FORCEPROP 2 LASTPIN (600 2800) $PN BR54
J 2
(590 2810);
DISPLAY 0.617021 (590 2810);
PAINT ORANGE (590 2810);
FORCEPROP 2 LASTPIN (600 2850) $PN BT8
J 2
(590 2860);
DISPLAY 0.617021 (590 2860);
PAINT ORANGE (590 2860);
FORCEPROP 2 LASTPIN (600 2900) $PN BR50
J 2
(590 2910);
DISPLAY 0.617021 (590 2910);
PAINT ORANGE (590 2910);
FORCEPROP 2 LASTPIN (600 2950) $PN BR20
J 2
(590 2960);
DISPLAY 0.617021 (590 2960);
PAINT ORANGE (590 2960);
FORCEPROP 2 LASTPIN (600 3000) $PN BN66
J 2
(590 3010);
DISPLAY 0.617021 (590 3010);
PAINT ORANGE (590 3010);
FORCEPROP 2 LASTPIN (600 3050) $PN BN52
J 2
(590 3060);
DISPLAY 0.617021 (590 3060);
PAINT ORANGE (590 3060);
FORCEPROP 2 LASTPIN (600 3100) $PN BN5
J 2
(590 3110);
DISPLAY 0.617021 (590 3110);
PAINT ORANGE (590 3110);
FORCEPROP 2 LASTPIN (600 3150) $PN BN59
J 2
(590 3160);
DISPLAY 0.617021 (590 3160);
PAINT ORANGE (590 3160);
FORCEPROP 2 LASTPIN (600 3200) $PN BN22
J 2
(590 3210);
DISPLAY 0.617021 (590 3210);
PAINT ORANGE (590 3210);
FORCEPROP 2 LASTPIN (600 3250) $PN BM9
J 2
(590 3260);
DISPLAY 0.617021 (590 3260);
PAINT ORANGE (590 3260);
FORCEPROP 2 LASTPIN (600 3300) $PN BM71
J 2
(590 3310);
DISPLAY 0.617021 (590 3310);
PAINT ORANGE (590 3310);
FORCEPROP 2 LASTPIN (600 3350) $PN BM69
J 2
(590 3360);
DISPLAY 0.617021 (590 3360);
PAINT ORANGE (590 3360);
FORCEPROP 2 LASTPIN (600 3400) $PN BM58
J 2
(590 3410);
DISPLAY 0.617021 (590 3410);
PAINT ORANGE (590 3410);
FORCEPROP 2 LASTPIN (600 3450) $PN BM50
J 2
(590 3460);
DISPLAY 0.617021 (590 3460);
PAINT ORANGE (590 3460);
FORCEPROP 2 LASTPIN (600 3500) $PN BM46
J 2
(590 3510);
DISPLAY 0.617021 (590 3510);
PAINT ORANGE (590 3510);
FORCEPROP 2 LASTPIN (600 3550) $PN BN37
J 2
(590 3560);
DISPLAY 0.617021 (590 3560);
PAINT ORANGE (590 3560);
FORCEPROP 2 LASTPIN (600 3600) $PN BM17
J 2
(590 3610);
DISPLAY 0.617021 (590 3610);
PAINT ORANGE (590 3610);
FORCEPROP 2 LASTPIN (600 3650) $PN BM13
J 2
(590 3660);
DISPLAY 0.617021 (590 3660);
PAINT ORANGE (590 3660);
FORCEPROP 2 LASTPIN (600 3700) $PN BL72
J 2
(590 3710);
DISPLAY 0.617021 (590 3710);
PAINT ORANGE (590 3710);
FORCEPROP 2 LASTPIN (600 3750) $PN BL70
J 2
(590 3760);
DISPLAY 0.617021 (590 3760);
PAINT ORANGE (590 3760);
FORCEPROP 2 LASTPIN (600 3800) $PN BL63
J 2
(590 3810);
DISPLAY 0.617021 (590 3810);
PAINT ORANGE (590 3810);
FORCEPROP 2 LASTPIN (600 3850) $PN BL5
J 2
(590 3860);
DISPLAY 0.617021 (590 3860);
PAINT ORANGE (590 3860);
FORCEPROP 2 LASTPIN (600 3900) $PN BL37
J 2
(590 3910);
DISPLAY 0.617021 (590 3910);
PAINT ORANGE (590 3910);
FORCEPROP 2 LASTPIN (600 3950) $PN BL68
J 2
(590 3960);
DISPLAY 0.617021 (590 3960);
PAINT ORANGE (590 3960);
FORCEPROP 2 LASTPIN (600 4000) $PN BL40
J 2
(590 4010);
DISPLAY 0.617021 (590 4010);
PAINT ORANGE (590 4010);
FORCEPROP 2 LASTPIN (600 4050) $PN BL22
J 2
(590 4060);
DISPLAY 0.617021 (590 4060);
PAINT ORANGE (590 4060);
FORCEPROP 2 LASTPIN (600 4100) $PN BK50
J 2
(590 4110);
DISPLAY 0.617021 (590 4110);
PAINT ORANGE (590 4110);
FORCEPROP 2 LASTPIN (600 4150) $PN BK42
J 2
(590 4160);
DISPLAY 0.617021 (590 4160);
PAINT ORANGE (590 4160);
FORCEPROP 2 LASTPIN (600 4200) $PN BK38
J 2
(590 4210);
DISPLAY 0.617021 (590 4210);
PAINT ORANGE (590 4210);
FORCEPROP 2 LASTPIN (600 4250) $PN BK35
J 2
(590 4260);
DISPLAY 0.617021 (590 4260);
PAINT ORANGE (590 4260);
FORCEPROP 2 LASTPIN (600 4300) $PN BK31
J 2
(590 4310);
DISPLAY 0.617021 (590 4310);
PAINT ORANGE (590 4310);
FORCEPROP 2 LASTPIN (600 4350) $PN BK27
J 2
(590 4360);
DISPLAY 0.617021 (590 4360);
PAINT ORANGE (590 4360);
FORCEPROP 2 LASTPIN (600 4400) $PN BK24
J 2
(590 4410);
DISPLAY 0.617021 (590 4410);
PAINT ORANGE (590 4410);
FORCEPROP 2 LASTPIN (600 1050) $PN BW52
J 2
(590 1060);
DISPLAY 0.617021 (590 1060);
PAINT ORANGE (590 1060);
FORCEPROP 2 LASTPIN (600 1300) $PN BU9
J 2
(590 1310);
DISPLAY 0.617021 (590 1310);
PAINT ORANGE (590 1310);
FORCEPROP 1 LAST PACK_TYPE BGA1
J 0
(650 4700);
PAINT SKYBLUE (650 4700);
DISPLAY INVISIBLE (650 4700);
FORCEPROP 2 LAST SEC_TYPE BGA1
J 0
(675 4750);
DISPLAY 1.021277 (675 4750);
PAINT ORANGE (675 4750);
DISPLAY INVISIBLE (675 4750);
FORCEPROP 2 LAST SEC 14
J 0
(675 4750);
DISPLAY 0.680851 (675 4750);
PAINT MONO (675 4750);
DISPLAY INVISIBLE (675 4750);
FORCEPROP 2 LAST CDS_LIB mstr_u_proc
J 0
(1200 2700);
PAINT ORANGE (1200 2700);
DISPLAY INVISIBLE (1200 2700);
FORCEPROP 0 LAST BOM_COST SB
J 0
(450 4350);
DISPLAY 1.361702 (450 4350);
PAINT ORANGE (450 4350);
DISPLAY INVISIBLE (450 4350);
FORCEPROP 2 LAST CDS_LOCATION U7C1
J 0
(675 4700);
DISPLAY 0.617021 (675 4700);
PAINT AQUA (675 4700);
DISPLAY INVISIBLE (675 4700);
FORCEPROP 1 LAST PATH I15
J 0
(1200 4600);
PAINT GREEN (1200 4600);
DISPLAY INVISIBLE (1200 4600);
FORCEPROP 0 LAST ROOM SB
J 0
(450 4250);
DISPLAY 1.361702 (450 4250);
PAINT ORANGE (450 4250);
DISPLAY INVISIBLE (450 4250);
FORCEADD LBG_CORE_QAT_EXT_D..13
(-1475 2725);
FORCEPROP 1 LAST LOCATION U7C1
J 0
(-1975 4750);
DISPLAY 0.617021 (-1975 4750);
PAINT AQUA (-1975 4750);
FORCEPROP 1 LAST PART_NUMBER H91415-002
J 0
(-2025 775);
DISPLAY 0.617021 (-2025 775);
PAINT BLUE (-2025 775);
FORCEPROP 1 LAST MATERIAL IC
J 0
(-2025 4625);
DISPLAY 0.617021 (-2025 4625);
PAINT SKYBLUE (-2025 4625);
FORCEPROP 2 LASTPIN (-875 975) $PN BJ68
J 0
(-865 985);
DISPLAY 0.617021 (-865 985);
PAINT ORANGE (-865 985);
FORCEPROP 2 LASTPIN (-875 1025) $PN BJ52
J 0
(-865 1035);
DISPLAY 0.617021 (-865 1035);
PAINT ORANGE (-865 1035);
FORCEPROP 2 LASTPIN (-875 1075) $PN BJ33
J 0
(-865 1085);
DISPLAY 0.617021 (-865 1085);
PAINT ORANGE (-865 1085);
FORCEPROP 2 LASTPIN (-875 1125) $PN BJ3
J 0
(-865 1135);
DISPLAY 0.617021 (-865 1135);
PAINT ORANGE (-865 1135);
FORCEPROP 2 LASTPIN (-875 1175) $PN BJ26
J 0
(-865 1185);
DISPLAY 0.617021 (-865 1185);
PAINT ORANGE (-865 1185);
FORCEPROP 2 LASTPIN (-875 1225) $PN BJ18
J 0
(-865 1235);
DISPLAY 0.617021 (-865 1235);
PAINT ORANGE (-865 1235);
FORCEPROP 2 LASTPIN (-875 1275) $PN BJ15
J 0
(-865 1285);
DISPLAY 0.617021 (-865 1285);
PAINT ORANGE (-865 1285);
FORCEPROP 2 LASTPIN (-875 1325) $PN BJ7
J 0
(-865 1335);
DISPLAY 0.617021 (-865 1335);
PAINT ORANGE (-865 1335);
FORCEPROP 2 LASTPIN (-875 1375) $PN BJ5
J 0
(-865 1385);
DISPLAY 0.617021 (-865 1385);
PAINT ORANGE (-865 1385);
FORCEPROP 2 LASTPIN (-875 1425) $PN BJ11
J 0
(-865 1435);
DISPLAY 0.617021 (-865 1435);
PAINT ORANGE (-865 1435);
FORCEPROP 2 LASTPIN (-875 1475) $PN BJ1
J 0
(-865 1485);
DISPLAY 0.617021 (-865 1485);
PAINT ORANGE (-865 1485);
FORCEPROP 2 LASTPIN (-875 1525) $PN BH54
J 0
(-865 1535);
DISPLAY 0.617021 (-865 1535);
PAINT ORANGE (-865 1535);
FORCEPROP 2 LASTPIN (-875 1575) $PN BH46
J 0
(-865 1585);
DISPLAY 0.617021 (-865 1585);
PAINT ORANGE (-865 1585);
FORCEPROP 2 LASTPIN (-875 1625) $PN BH42
J 0
(-865 1635);
DISPLAY 0.617021 (-865 1635);
PAINT ORANGE (-865 1635);
FORCEPROP 2 LASTPIN (-875 1675) $PN BH38
J 0
(-865 1685);
DISPLAY 0.617021 (-865 1685);
PAINT ORANGE (-865 1685);
FORCEPROP 2 LASTPIN (-875 1725) $PN BH27
J 0
(-865 1735);
DISPLAY 0.617021 (-865 1735);
PAINT ORANGE (-865 1735);
FORCEPROP 2 LASTPIN (-875 1775) $PN BG63
J 0
(-865 1785);
DISPLAY 0.617021 (-865 1785);
PAINT ORANGE (-865 1785);
FORCEPROP 2 LASTPIN (-875 1825) $PN BG59
J 0
(-865 1835);
DISPLAY 0.617021 (-865 1835);
PAINT ORANGE (-865 1835);
FORCEPROP 2 LASTPIN (-875 1875) $PN BG48
J 0
(-865 1885);
DISPLAY 0.617021 (-865 1885);
PAINT ORANGE (-865 1885);
FORCEPROP 2 LASTPIN (-875 1925) $PN BG33
J 0
(-865 1935);
DISPLAY 0.617021 (-865 1935);
PAINT ORANGE (-865 1935);
FORCEPROP 2 LASTPIN (-875 1975) $PN BF9
J 0
(-865 1985);
DISPLAY 0.617021 (-865 1985);
PAINT ORANGE (-865 1985);
FORCEPROP 2 LASTPIN (-875 2025) $PN BF68
J 0
(-865 2035);
DISPLAY 0.617021 (-865 2035);
PAINT ORANGE (-865 2035);
FORCEPROP 2 LASTPIN (-875 2075) $PN BF65
J 0
(-865 2085);
DISPLAY 0.617021 (-865 2085);
PAINT ORANGE (-865 2085);
FORCEPROP 2 LASTPIN (-875 2125) $PN BF61
J 0
(-865 2135);
DISPLAY 0.617021 (-865 2135);
PAINT ORANGE (-865 2135);
FORCEPROP 2 LASTPIN (-875 2175) $PN BF58
J 0
(-865 2185);
DISPLAY 0.617021 (-865 2185);
PAINT ORANGE (-865 2185);
FORCEPROP 2 LASTPIN (-875 2225) $PN BF50
J 0
(-865 2235);
DISPLAY 0.617021 (-865 2235);
PAINT ORANGE (-865 2235);
FORCEPROP 2 LASTPIN (-875 2275) $PN BF5
J 0
(-865 2285);
DISPLAY 0.617021 (-865 2285);
PAINT ORANGE (-865 2285);
FORCEPROP 2 LASTPIN (-875 2325) $PN BF42
J 0
(-865 2335);
DISPLAY 0.617021 (-865 2335);
PAINT ORANGE (-865 2335);
FORCEPROP 2 LASTPIN (-875 2375) $PN BF38
J 0
(-865 2385);
DISPLAY 0.617021 (-865 2385);
PAINT ORANGE (-865 2385);
FORCEPROP 2 LASTPIN (-875 2425) $PN BF27
J 0
(-865 2435);
DISPLAY 0.617021 (-865 2435);
PAINT ORANGE (-865 2435);
FORCEPROP 2 LASTPIN (-875 2475) $PN BF24
J 0
(-865 2485);
DISPLAY 0.617021 (-865 2485);
PAINT ORANGE (-865 2485);
FORCEPROP 2 LASTPIN (-875 2525) $PN BF20
J 0
(-865 2535);
DISPLAY 0.617021 (-865 2535);
PAINT ORANGE (-865 2535);
FORCEPROP 2 LASTPIN (-875 2575) $PN BG44
J 0
(-865 2585);
DISPLAY 0.617021 (-865 2585);
PAINT ORANGE (-865 2585);
FORCEPROP 2 LASTPIN (-875 2625) $PN BF54
J 0
(-865 2635);
DISPLAY 0.617021 (-865 2635);
PAINT ORANGE (-865 2635);
FORCEPROP 2 LASTPIN (-875 2675) $PN BF17
J 0
(-865 2685);
DISPLAY 0.617021 (-865 2685);
PAINT ORANGE (-865 2685);
FORCEPROP 2 LASTPIN (-875 2725) $PN BF13
J 0
(-865 2735);
DISPLAY 0.617021 (-865 2735);
PAINT ORANGE (-865 2735);
FORCEPROP 2 LASTPIN (-875 2775) $PN BE66
J 0
(-865 2785);
DISPLAY 0.617021 (-865 2785);
PAINT ORANGE (-865 2785);
FORCEPROP 2 LASTPIN (-875 2825) $PN BE63
J 0
(-865 2835);
DISPLAY 0.617021 (-865 2835);
PAINT ORANGE (-865 2835);
FORCEPROP 2 LASTPIN (-875 2875) $PN BE59
J 0
(-865 2885);
DISPLAY 0.617021 (-865 2885);
PAINT ORANGE (-865 2885);
FORCEPROP 2 LASTPIN (-875 2925) $PN BE56
J 0
(-865 2935);
DISPLAY 0.617021 (-865 2935);
PAINT ORANGE (-865 2935);
FORCEPROP 2 LASTPIN (-875 2975) $PN BE37
J 0
(-865 2985);
DISPLAY 0.617021 (-865 2985);
PAINT ORANGE (-865 2985);
FORCEPROP 2 LASTPIN (-875 3025) $PN BE33
J 0
(-865 3035);
DISPLAY 0.617021 (-865 3035);
PAINT ORANGE (-865 3035);
FORCEPROP 2 LASTPIN (-875 3075) $PN BE29
J 0
(-865 3085);
DISPLAY 0.617021 (-865 3085);
PAINT ORANGE (-865 3085);
FORCEPROP 2 LASTPIN (-875 3125) $PN BD68
J 0
(-865 3135);
DISPLAY 0.617021 (-865 3135);
PAINT ORANGE (-865 3135);
FORCEPROP 2 LASTPIN (-875 3175) $PN BD54
J 0
(-865 3185);
DISPLAY 0.617021 (-865 3185);
PAINT ORANGE (-865 3185);
FORCEPROP 2 LASTPIN (-875 3225) $PN BD50
J 0
(-865 3235);
DISPLAY 0.617021 (-865 3235);
PAINT ORANGE (-865 3235);
FORCEPROP 2 LASTPIN (-875 3275) $PN BD5
J 0
(-865 3285);
DISPLAY 0.617021 (-865 3285);
PAINT ORANGE (-865 3285);
FORCEPROP 2 LASTPIN (-875 3325) $PN BD35
J 0
(-865 3335);
DISPLAY 0.617021 (-865 3335);
PAINT ORANGE (-865 3335);
FORCEPROP 2 LASTPIN (-875 3375) $PN BD31
J 0
(-865 3385);
DISPLAY 0.617021 (-865 3385);
PAINT ORANGE (-865 3385);
FORCEPROP 2 LASTPIN (-875 3425) $PN BD27
J 0
(-865 3435);
DISPLAY 0.617021 (-865 3435);
PAINT ORANGE (-865 3435);
FORCEPROP 2 LASTPIN (-875 3475) $PN BD24
J 0
(-865 3485);
DISPLAY 0.617021 (-865 3485);
PAINT ORANGE (-865 3485);
FORCEPROP 2 LASTPIN (-875 3525) $PN BC71
J 0
(-865 3535);
DISPLAY 0.617021 (-865 3535);
PAINT ORANGE (-865 3535);
FORCEPROP 2 LASTPIN (-875 3575) $PN BC69
J 0
(-865 3585);
DISPLAY 0.617021 (-865 3585);
PAINT ORANGE (-865 3585);
FORCEPROP 2 LASTPIN (-875 3625) $PN BB72
J 0
(-865 3635);
DISPLAY 0.617021 (-865 3635);
PAINT ORANGE (-865 3635);
FORCEPROP 2 LASTPIN (-875 3675) $PN BB70
J 0
(-865 3685);
DISPLAY 0.617021 (-865 3685);
PAINT ORANGE (-865 3685);
FORCEPROP 2 LASTPIN (-875 3725) $PN BB68
J 0
(-865 3735);
DISPLAY 0.617021 (-865 3735);
PAINT ORANGE (-865 3735);
FORCEPROP 2 LASTPIN (-875 3775) $PN BB66
J 0
(-865 3785);
DISPLAY 0.617021 (-865 3785);
PAINT ORANGE (-865 3785);
FORCEPROP 2 LASTPIN (-875 3825) $PN BB59
J 0
(-865 3835);
DISPLAY 0.617021 (-865 3835);
PAINT ORANGE (-865 3835);
FORCEPROP 2 LASTPIN (-875 3875) $PN BB44
J 0
(-865 3885);
DISPLAY 0.617021 (-865 3885);
PAINT ORANGE (-865 3885);
FORCEPROP 2 LASTPIN (-875 3925) $PN BB22
J 0
(-865 3935);
DISPLAY 0.617021 (-865 3935);
PAINT ORANGE (-865 3935);
FORCEPROP 2 LASTPIN (-875 3975) $PN BB18
J 0
(-865 3985);
DISPLAY 0.617021 (-865 3985);
PAINT ORANGE (-865 3985);
FORCEPROP 2 LASTPIN (-875 4025) $PN BB15
J 0
(-865 4035);
DISPLAY 0.617021 (-865 4035);
PAINT ORANGE (-865 4035);
FORCEPROP 2 LASTPIN (-875 4075) $PN BB11
J 0
(-865 4085);
DISPLAY 0.617021 (-865 4085);
PAINT ORANGE (-865 4085);
FORCEPROP 2 LASTPIN (-875 4125) $PN BB7
J 0
(-865 4135);
DISPLAY 0.617021 (-865 4135);
PAINT ORANGE (-865 4135);
FORCEPROP 2 LASTPIN (-875 4175) $PN BB5
J 0
(-865 4185);
DISPLAY 0.617021 (-865 4185);
PAINT ORANGE (-865 4185);
FORCEPROP 2 LASTPIN (-875 4225) $PN BA58
J 0
(-865 4235);
DISPLAY 0.617021 (-865 4235);
PAINT ORANGE (-865 4235);
FORCEPROP 2 LASTPIN (-875 4275) $PN BA54
J 0
(-865 4285);
DISPLAY 0.617021 (-865 4285);
PAINT ORANGE (-865 4285);
FORCEPROP 2 LASTPIN (-875 4325) $PN BA50
J 0
(-865 4335);
DISPLAY 0.617021 (-865 4335);
PAINT ORANGE (-865 4335);
FORCEPROP 2 LASTPIN (-875 4375) $PN AY68
J 0
(-865 4385);
DISPLAY 0.617021 (-865 4385);
PAINT ORANGE (-865 4385);
FORCEPROP 2 LASTPIN (-875 4425) $PN AY63
J 0
(-865 4435);
DISPLAY 0.617021 (-865 4435);
PAINT ORANGE (-865 4435);
FORCEPROP 2 LASTPIN (-2075 975) $PN AY56
J 2
(-2085 985);
DISPLAY 0.617021 (-2085 985);
PAINT ORANGE (-2085 985);
FORCEPROP 2 LASTPIN (-2075 1025) $PN AY22
J 2
(-2085 1035);
DISPLAY 0.617021 (-2085 1035);
PAINT ORANGE (-2085 1035);
FORCEPROP 2 LASTPIN (-2075 1075) $PN AY5
J 2
(-2085 1085);
DISPLAY 0.617021 (-2085 1085);
PAINT ORANGE (-2085 1085);
FORCEPROP 2 LASTPIN (-2075 1125) $PN AW61
J 2
(-2085 1135);
DISPLAY 0.617021 (-2085 1135);
PAINT ORANGE (-2085 1135);
FORCEPROP 2 LASTPIN (-2075 1175) $PN AW58
J 2
(-2085 1185);
DISPLAY 0.617021 (-2085 1185);
PAINT ORANGE (-2085 1185);
FORCEPROP 2 LASTPIN (-2075 1225) $PN AW50
J 2
(-2085 1235);
DISPLAY 0.617021 (-2085 1235);
PAINT ORANGE (-2085 1235);
FORCEPROP 2 LASTPIN (-2075 1275) $PN AW46
J 2
(-2085 1285);
DISPLAY 0.617021 (-2085 1285);
PAINT ORANGE (-2085 1285);
FORCEPROP 2 LASTPIN (-2075 1325) $PN AW41
J 2
(-2085 1335);
DISPLAY 0.617021 (-2085 1335);
PAINT ORANGE (-2085 1335);
FORCEPROP 2 LASTPIN (-2075 1375) $PN AW39
J 2
(-2085 1385);
DISPLAY 0.617021 (-2085 1385);
PAINT ORANGE (-2085 1385);
FORCEPROP 2 LASTPIN (-2075 1425) $PN AW37
J 2
(-2085 1435);
DISPLAY 0.617021 (-2085 1435);
PAINT ORANGE (-2085 1435);
FORCEPROP 2 LASTPIN (-2075 1475) $PN AW36
J 2
(-2085 1485);
DISPLAY 0.617021 (-2085 1485);
PAINT ORANGE (-2085 1485);
FORCEPROP 2 LASTPIN (-2075 1525) $PN AW34
J 2
(-2085 1535);
DISPLAY 0.617021 (-2085 1535);
PAINT ORANGE (-2085 1535);
FORCEPROP 2 LASTPIN (-2075 1575) $PN AW32
J 2
(-2085 1585);
DISPLAY 0.617021 (-2085 1585);
PAINT ORANGE (-2085 1585);
FORCEPROP 2 LASTPIN (-2075 1625) $PN AW30
J 2
(-2085 1635);
DISPLAY 0.617021 (-2085 1635);
PAINT ORANGE (-2085 1635);
FORCEPROP 2 LASTPIN (-2075 1675) $PN AW26
J 2
(-2085 1685);
DISPLAY 0.617021 (-2085 1685);
PAINT ORANGE (-2085 1685);
FORCEPROP 2 LASTPIN (-2075 1725) $PN AW17
J 2
(-2085 1735);
DISPLAY 0.617021 (-2085 1735);
PAINT ORANGE (-2085 1735);
FORCEPROP 2 LASTPIN (-2075 1775) $PN AW13
J 2
(-2085 1785);
DISPLAY 0.617021 (-2085 1785);
PAINT ORANGE (-2085 1785);
FORCEPROP 2 LASTPIN (-2075 1825) $PN AW9
J 2
(-2085 1835);
DISPLAY 0.617021 (-2085 1835);
PAINT ORANGE (-2085 1835);
FORCEPROP 2 LASTPIN (-2075 1875) $PN AV68
J 2
(-2085 1885);
DISPLAY 0.617021 (-2085 1885);
PAINT ORANGE (-2085 1885);
FORCEPROP 2 LASTPIN (-2075 1925) $PN AV59
J 2
(-2085 1935);
DISPLAY 0.617021 (-2085 1935);
PAINT ORANGE (-2085 1935);
FORCEPROP 2 LASTPIN (-2075 1975) $PN AV22
J 2
(-2085 1985);
DISPLAY 0.617021 (-2085 1985);
PAINT ORANGE (-2085 1985);
FORCEPROP 2 LASTPIN (-2075 2025) $PN AV5
J 2
(-2085 2035);
DISPLAY 0.617021 (-2085 2035);
PAINT ORANGE (-2085 2035);
FORCEPROP 2 LASTPIN (-2075 2075) $PN AU61
J 2
(-2085 2085);
DISPLAY 0.617021 (-2085 2085);
PAINT ORANGE (-2085 2085);
FORCEPROP 2 LASTPIN (-2075 2125) $PN AU54
J 2
(-2085 2135);
DISPLAY 0.617021 (-2085 2135);
PAINT ORANGE (-2085 2135);
FORCEPROP 2 LASTPIN (-2075 2175) $PN AU50
J 2
(-2085 2185);
DISPLAY 0.617021 (-2085 2185);
PAINT ORANGE (-2085 2185);
FORCEPROP 2 LASTPIN (-2075 2225) $PN AU46
J 2
(-2085 2235);
DISPLAY 0.617021 (-2085 2235);
PAINT ORANGE (-2085 2235);
FORCEPROP 2 LASTPIN (-2075 2275) $PN AU41
J 2
(-2085 2285);
DISPLAY 0.617021 (-2085 2285);
PAINT ORANGE (-2085 2285);
FORCEPROP 2 LASTPIN (-2075 2325) $PN AE22
J 2
(-2085 2335);
DISPLAY 0.617021 (-2085 2335);
PAINT ORANGE (-2085 2335);
FORCEPROP 2 LASTPIN (-2075 2375) $PN AU30
J 2
(-2085 2385);
DISPLAY 0.617021 (-2085 2385);
PAINT ORANGE (-2085 2385);
FORCEPROP 2 LASTPIN (-2075 2425) $PN AU26
J 2
(-2085 2435);
DISPLAY 0.617021 (-2085 2435);
PAINT ORANGE (-2085 2435);
FORCEPROP 2 LASTPIN (-2075 2475) $PN AT59
J 2
(-2085 2485);
DISPLAY 0.617021 (-2085 2485);
PAINT ORANGE (-2085 2485);
FORCEPROP 2 LASTPIN (-2075 2525) $PN AT46
J 2
(-2085 2535);
DISPLAY 0.617021 (-2085 2535);
PAINT ORANGE (-2085 2535);
FORCEPROP 2 LASTPIN (-2075 2575) $PN AT41
J 2
(-2085 2585);
DISPLAY 0.617021 (-2085 2585);
PAINT ORANGE (-2085 2585);
FORCEPROP 2 LASTPIN (-2075 2625) $PN AT30
J 2
(-2085 2635);
DISPLAY 0.617021 (-2085 2635);
PAINT ORANGE (-2085 2635);
FORCEPROP 2 LASTPIN (-2075 2675) $PN AT26
J 2
(-2085 2685);
DISPLAY 0.617021 (-2085 2685);
PAINT ORANGE (-2085 2685);
FORCEPROP 2 LASTPIN (-2075 2725) $PN AT22
J 2
(-2085 2735);
DISPLAY 0.617021 (-2085 2735);
PAINT ORANGE (-2085 2735);
FORCEPROP 2 LASTPIN (-2075 2775) $PN AT18
J 2
(-2085 2785);
DISPLAY 0.617021 (-2085 2785);
PAINT ORANGE (-2085 2785);
FORCEPROP 2 LASTPIN (-2075 2825) $PN AT15
J 2
(-2085 2835);
DISPLAY 0.617021 (-2085 2835);
PAINT ORANGE (-2085 2835);
FORCEPROP 2 LASTPIN (-2075 2875) $PN AT11
J 2
(-2085 2885);
DISPLAY 0.617021 (-2085 2885);
PAINT ORANGE (-2085 2885);
FORCEPROP 2 LASTPIN (-2075 2925) $PN AT7
J 2
(-2085 2935);
DISPLAY 0.617021 (-2085 2935);
PAINT ORANGE (-2085 2935);
FORCEPROP 2 LASTPIN (-2075 2975) $PN AR72
J 2
(-2085 2985);
DISPLAY 0.617021 (-2085 2985);
PAINT ORANGE (-2085 2985);
FORCEPROP 2 LASTPIN (-2075 3025) $PN AR70
J 2
(-2085 3035);
DISPLAY 0.617021 (-2085 3035);
PAINT ORANGE (-2085 3035);
FORCEPROP 2 LASTPIN (-2075 3075) $PN AR68
J 2
(-2085 3085);
DISPLAY 0.617021 (-2085 3085);
PAINT ORANGE (-2085 3085);
FORCEPROP 2 LASTPIN (-2075 3125) $PN AR65
J 2
(-2085 3135);
DISPLAY 0.617021 (-2085 3135);
PAINT ORANGE (-2085 3135);
FORCEPROP 2 LASTPIN (-2075 3175) $PN AR58
J 2
(-2085 3185);
DISPLAY 0.617021 (-2085 3185);
PAINT ORANGE (-2085 3185);
FORCEPROP 2 LASTPIN (-2075 3225) $PN AR50
J 2
(-2085 3235);
DISPLAY 0.617021 (-2085 3235);
PAINT ORANGE (-2085 3235);
FORCEPROP 2 LASTPIN (-2075 3275) $PN AR5
J 2
(-2085 3285);
DISPLAY 0.617021 (-2085 3285);
PAINT ORANGE (-2085 3285);
FORCEPROP 2 LASTPIN (-2075 3325) $PN AP66
J 2
(-2085 3335);
DISPLAY 0.617021 (-2085 3335);
PAINT ORANGE (-2085 3335);
FORCEPROP 2 LASTPIN (-2075 3375) $PN AP52
J 2
(-2085 3385);
DISPLAY 0.617021 (-2085 3385);
PAINT ORANGE (-2085 3385);
FORCEPROP 2 LASTPIN (-2075 3425) $PN AP46
J 2
(-2085 3435);
DISPLAY 0.617021 (-2085 3435);
PAINT ORANGE (-2085 3435);
FORCEPROP 2 LASTPIN (-2075 3475) $PN AP41
J 2
(-2085 3485);
DISPLAY 0.617021 (-2085 3485);
PAINT ORANGE (-2085 3485);
FORCEPROP 2 LASTPIN (-2075 3525) $PN AP4
J 2
(-2085 3535);
DISPLAY 0.617021 (-2085 3535);
PAINT ORANGE (-2085 3535);
FORCEPROP 2 LASTPIN (-2075 3575) $PN AP30
J 2
(-2085 3585);
DISPLAY 0.617021 (-2085 3585);
PAINT ORANGE (-2085 3585);
FORCEPROP 2 LASTPIN (-2075 3625) $PN AP26
J 2
(-2085 3635);
DISPLAY 0.617021 (-2085 3635);
PAINT ORANGE (-2085 3635);
FORCEPROP 2 LASTPIN (-2075 3675) $PN AP2
J 2
(-2085 3685);
DISPLAY 0.617021 (-2085 3685);
PAINT ORANGE (-2085 3685);
FORCEPROP 2 LASTPIN (-2075 3725) $PN AN9
J 2
(-2085 3735);
DISPLAY 0.617021 (-2085 3735);
PAINT ORANGE (-2085 3735);
FORCEPROP 2 LASTPIN (-2075 3775) $PN AN58
J 2
(-2085 3785);
DISPLAY 0.617021 (-2085 3785);
PAINT ORANGE (-2085 3785);
FORCEPROP 2 LASTPIN (-2075 3825) $PN AN5
J 2
(-2085 3835);
DISPLAY 0.617021 (-2085 3835);
PAINT ORANGE (-2085 3835);
FORCEPROP 2 LASTPIN (-2075 3875) $PN AN20
J 2
(-2085 3885);
DISPLAY 0.617021 (-2085 3885);
PAINT ORANGE (-2085 3885);
FORCEPROP 2 LASTPIN (-2075 3925) $PN AP22
J 2
(-2085 3935);
DISPLAY 0.617021 (-2085 3935);
PAINT ORANGE (-2085 3935);
FORCEPROP 2 LASTPIN (-2075 3975) $PN AN68
J 2
(-2085 3985);
DISPLAY 0.617021 (-2085 3985);
PAINT ORANGE (-2085 3985);
FORCEPROP 2 LASTPIN (-2075 4075) $PN AN13
J 2
(-2085 4085);
DISPLAY 0.617021 (-2085 4085);
PAINT ORANGE (-2085 4085);
FORCEPROP 2 LASTPIN (-2075 4125) $PN AM46
J 2
(-2085 4135);
DISPLAY 0.617021 (-2085 4135);
PAINT ORANGE (-2085 4135);
FORCEPROP 2 LASTPIN (-2075 4175) $PN AM41
J 2
(-2085 4185);
DISPLAY 0.617021 (-2085 4185);
PAINT ORANGE (-2085 4185);
FORCEPROP 2 LASTPIN (-2075 4225) $PN AM30
J 2
(-2085 4235);
DISPLAY 0.617021 (-2085 4235);
PAINT ORANGE (-2085 4235);
FORCEPROP 2 LASTPIN (-2075 4275) $PN AM26
J 2
(-2085 4285);
DISPLAY 0.617021 (-2085 4285);
PAINT ORANGE (-2085 4285);
FORCEPROP 2 LASTPIN (-2075 4325) $PN AL72
J 2
(-2085 4335);
DISPLAY 0.617021 (-2085 4335);
PAINT ORANGE (-2085 4335);
FORCEPROP 2 LASTPIN (-2075 4375) $PN AL70
J 2
(-2085 4385);
DISPLAY 0.617021 (-2085 4385);
PAINT ORANGE (-2085 4385);
FORCEPROP 2 LASTPIN (-2075 4425) $PN AL68
J 2
(-2085 4435);
DISPLAY 0.617021 (-2085 4435);
PAINT ORANGE (-2085 4435);
FORCEPROP 2 LASTPIN (-2075 4025) $PN AN17
J 2
(-2085 4035);
DISPLAY 0.617021 (-2085 4035);
PAINT ORANGE (-2085 4035);
FORCEPROP 1 LAST PACK_TYPE BGA1
J 0
(-2025 4725);
PAINT SKYBLUE (-2025 4725);
DISPLAY INVISIBLE (-2025 4725);
FORCEPROP 2 LAST SEC_TYPE BGA1
J 0
(-1975 4800);
DISPLAY 1.021277 (-1975 4800);
PAINT ORANGE (-1975 4800);
DISPLAY INVISIBLE (-1975 4800);
FORCEPROP 2 LAST SEC 13
J 0
(-1975 4800);
DISPLAY 0.680851 (-1975 4800);
PAINT MONO (-1975 4800);
DISPLAY INVISIBLE (-1975 4800);
FORCEPROP 2 LAST CDS_LIB mstr_u_proc
J 0
(-1475 2725);
PAINT ORANGE (-1475 2725);
DISPLAY INVISIBLE (-1475 2725);
FORCEPROP 0 LAST BOM_COST SB
J 0
(-2225 4375);
DISPLAY 1.361702 (-2225 4375);
PAINT ORANGE (-2225 4375);
DISPLAY INVISIBLE (-2225 4375);
FORCEPROP 2 LAST CDS_LOCATION U7C1
J 0
(-1975 4750);
DISPLAY 0.617021 (-1975 4750);
PAINT AQUA (-1975 4750);
DISPLAY INVISIBLE (-1975 4750);
FORCEPROP 1 LAST PATH I16
J 0
(-1475 4625);
PAINT GREEN (-1475 4625);
DISPLAY INVISIBLE (-1475 4625);
FORCEPROP 0 LAST ROOM SB
J 0
(-2225 4275);
DISPLAY 1.361702 (-2225 4275);
PAINT ORANGE (-2225 4275);
DISPLAY INVISIBLE (-2225 4275);
FORCEADD LBG_CORE_QAT_EXT_D..12
(-4000 2700);
FORCEPROP 1 LAST PART_NUMBER H91415-002
J 0
(-4550 750);
DISPLAY 0.617021 (-4550 750);
PAINT BLUE (-4550 750);
FORCEPROP 1 LAST MATERIAL IC
J 0
(-4550 4600);
DISPLAY 0.617021 (-4550 4600);
PAINT SKYBLUE (-4550 4600);
FORCEPROP 2 LASTPIN (-3400 950) $PN AL59
J 0
(-3390 960);
DISPLAY 0.617021 (-3390 960);
PAINT ORANGE (-3390 960);
FORCEPROP 2 LASTPIN (-3400 1000) $PN AL52
J 0
(-3390 1010);
DISPLAY 0.617021 (-3390 1010);
PAINT ORANGE (-3390 1010);
FORCEPROP 2 LASTPIN (-3400 1050) $PN AL5
J 0
(-3390 1060);
DISPLAY 0.617021 (-3390 1060);
PAINT ORANGE (-3390 1060);
FORCEPROP 2 LASTPIN (-3400 1100) $PN AL22
J 0
(-3390 1110);
DISPLAY 0.617021 (-3390 1110);
PAINT ORANGE (-3390 1110);
FORCEPROP 2 LASTPIN (-3400 1150) $PN AK71
J 0
(-3390 1160);
DISPLAY 0.617021 (-3390 1160);
PAINT ORANGE (-3390 1160);
FORCEPROP 2 LASTPIN (-3400 1200) $PN AK69
J 0
(-3390 1210);
DISPLAY 0.617021 (-3390 1210);
PAINT ORANGE (-3390 1210);
FORCEPROP 2 LASTPIN (-3400 1300) $PN AK58
J 0
(-3390 1310);
DISPLAY 0.617021 (-3390 1310);
PAINT ORANGE (-3390 1310);
FORCEPROP 2 LASTPIN (-3400 1350) $PN AK48
J 0
(-3390 1360);
DISPLAY 0.617021 (-3390 1360);
PAINT ORANGE (-3390 1360);
FORCEPROP 2 LASTPIN (-3400 1400) $PN AK46
J 0
(-3390 1410);
DISPLAY 0.617021 (-3390 1410);
PAINT ORANGE (-3390 1410);
FORCEPROP 2 LASTPIN (-3400 1450) $PN AK41
J 0
(-3390 1460);
DISPLAY 0.617021 (-3390 1460);
PAINT ORANGE (-3390 1460);
FORCEPROP 2 LASTPIN (-3400 1500) $PN AK26
J 0
(-3390 1510);
DISPLAY 0.617021 (-3390 1510);
PAINT ORANGE (-3390 1510);
FORCEPROP 2 LASTPIN (-3400 1550) $PN AJ7
J 0
(-3390 1560);
DISPLAY 0.617021 (-3390 1560);
PAINT ORANGE (-3390 1560);
FORCEPROP 2 LASTPIN (-3400 1600) $PN AJ68
J 0
(-3390 1610);
DISPLAY 0.617021 (-3390 1610);
PAINT ORANGE (-3390 1610);
FORCEPROP 2 LASTPIN (-3400 1650) $PN AJ66
J 0
(-3390 1660);
DISPLAY 0.617021 (-3390 1660);
PAINT ORANGE (-3390 1660);
FORCEPROP 2 LASTPIN (-3400 1700) $PN AJ59
J 0
(-3390 1710);
DISPLAY 0.617021 (-3390 1710);
PAINT ORANGE (-3390 1710);
FORCEPROP 2 LASTPIN (-3400 1750) $PN AJ52
J 0
(-3390 1760);
DISPLAY 0.617021 (-3390 1760);
PAINT ORANGE (-3390 1760);
FORCEPROP 2 LASTPIN (-3400 1800) $PN AJ5
J 0
(-3390 1810);
DISPLAY 0.617021 (-3390 1810);
PAINT ORANGE (-3390 1810);
FORCEPROP 2 LASTPIN (-3400 1850) $PN AJ41
J 0
(-3390 1860);
DISPLAY 0.617021 (-3390 1860);
PAINT ORANGE (-3390 1860);
FORCEPROP 2 LASTPIN (-3400 1900) $PN AJ39
J 0
(-3390 1910);
DISPLAY 0.617021 (-3390 1910);
PAINT ORANGE (-3390 1910);
FORCEPROP 2 LASTPIN (-3400 1950) $PN AJ37
J 0
(-3390 1960);
DISPLAY 0.617021 (-3390 1960);
PAINT ORANGE (-3390 1960);
FORCEPROP 2 LASTPIN (-3400 2000) $PN AJ36
J 0
(-3390 2010);
DISPLAY 0.617021 (-3390 2010);
PAINT ORANGE (-3390 2010);
FORCEPROP 2 LASTPIN (-3400 2050) $PN AJ34
J 0
(-3390 2060);
DISPLAY 0.617021 (-3390 2060);
PAINT ORANGE (-3390 2060);
FORCEPROP 2 LASTPIN (-3400 2100) $PN AJ30
J 0
(-3390 2110);
DISPLAY 0.617021 (-3390 2110);
PAINT ORANGE (-3390 2110);
FORCEPROP 2 LASTPIN (-3400 2150) $PN AJ26
J 0
(-3390 2160);
DISPLAY 0.617021 (-3390 2160);
PAINT ORANGE (-3390 2160);
FORCEPROP 2 LASTPIN (-3400 2200) $PN AJ22
J 0
(-3390 2210);
DISPLAY 0.617021 (-3390 2210);
PAINT ORANGE (-3390 2210);
FORCEPROP 2 LASTPIN (-3400 2250) $PN AJ18
J 0
(-3390 2260);
DISPLAY 0.617021 (-3390 2260);
PAINT ORANGE (-3390 2260);
FORCEPROP 2 LASTPIN (-3400 2300) $PN AJ15
J 0
(-3390 2310);
DISPLAY 0.617021 (-3390 2310);
PAINT ORANGE (-3390 2310);
FORCEPROP 2 LASTPIN (-3400 2350) $PN AK30
J 0
(-3390 2360);
DISPLAY 0.617021 (-3390 2360);
PAINT ORANGE (-3390 2360);
FORCEPROP 2 LASTPIN (-3400 2400) $PN AJ56
J 0
(-3390 2410);
DISPLAY 0.617021 (-3390 2410);
PAINT ORANGE (-3390 2410);
FORCEPROP 2 LASTPIN (-3400 2450) $PN AJ32
J 0
(-3390 2460);
DISPLAY 0.617021 (-3390 2460);
PAINT ORANGE (-3390 2460);
FORCEPROP 2 LASTPIN (-3400 2500) $PN AJ11
J 0
(-3390 2510);
DISPLAY 0.617021 (-3390 2510);
PAINT ORANGE (-3390 2510);
FORCEPROP 2 LASTPIN (-3400 2550) $PN AH20
J 0
(-3390 2560);
DISPLAY 0.617021 (-3390 2560);
PAINT ORANGE (-3390 2560);
FORCEPROP 2 LASTPIN (-3400 2600) $PN AG66
J 0
(-3390 2610);
DISPLAY 0.617021 (-3390 2610);
PAINT ORANGE (-3390 2610);
FORCEPROP 2 LASTPIN (-3400 2650) $PN AG59
J 0
(-3390 2660);
DISPLAY 0.617021 (-3390 2660);
PAINT ORANGE (-3390 2660);
FORCEPROP 2 LASTPIN (-3400 2700) $PN AG56
J 0
(-3390 2710);
DISPLAY 0.617021 (-3390 2710);
PAINT ORANGE (-3390 2710);
FORCEPROP 2 LASTPIN (-3400 2750) $PN AG52
J 0
(-3390 2760);
DISPLAY 0.617021 (-3390 2760);
PAINT ORANGE (-3390 2760);
FORCEPROP 2 LASTPIN (-3400 2800) $PN AG43
J 0
(-3390 2810);
DISPLAY 0.617021 (-3390 2810);
PAINT ORANGE (-3390 2810);
FORCEPROP 2 LASTPIN (-3400 2850) $PN AG41
J 0
(-3390 2860);
DISPLAY 0.617021 (-3390 2860);
PAINT ORANGE (-3390 2860);
FORCEPROP 2 LASTPIN (-3400 2900) $PN AG30
J 0
(-3390 2910);
DISPLAY 0.617021 (-3390 2910);
PAINT ORANGE (-3390 2910);
FORCEPROP 2 LASTPIN (-3400 2950) $PN AG26
J 0
(-3390 2960);
DISPLAY 0.617021 (-3390 2960);
PAINT ORANGE (-3390 2960);
FORCEPROP 2 LASTPIN (-3400 3000) $PN AF68
J 0
(-3390 3010);
DISPLAY 0.617021 (-3390 3010);
PAINT ORANGE (-3390 3010);
FORCEPROP 2 LASTPIN (-3400 3050) $PN AF3
J 0
(-3390 3060);
DISPLAY 0.617021 (-3390 3060);
PAINT ORANGE (-3390 3060);
FORCEPROP 2 LASTPIN (-3400 3100) $PN AF24
J 0
(-3390 3110);
DISPLAY 0.617021 (-3390 3110);
PAINT ORANGE (-3390 3110);
FORCEPROP 2 LASTPIN (-3400 3150) $PN AF17
J 0
(-3390 3160);
DISPLAY 0.617021 (-3390 3160);
PAINT ORANGE (-3390 3160);
FORCEPROP 2 LASTPIN (-3400 3200) $PN AF9
J 0
(-3390 3210);
DISPLAY 0.617021 (-3390 3210);
PAINT ORANGE (-3390 3210);
FORCEPROP 2 LASTPIN (-3400 3250) $PN AF5
J 0
(-3390 3260);
DISPLAY 0.617021 (-3390 3260);
PAINT ORANGE (-3390 3260);
FORCEPROP 2 LASTPIN (-3400 3300) $PN AF13
J 0
(-3390 3310);
DISPLAY 0.617021 (-3390 3310);
PAINT ORANGE (-3390 3310);
FORCEPROP 2 LASTPIN (-3400 3350) $PN AF1
J 0
(-3390 3360);
DISPLAY 0.617021 (-3390 3360);
PAINT ORANGE (-3390 3360);
FORCEPROP 2 LASTPIN (-3400 3400) $PN AE66
J 0
(-3390 3410);
DISPLAY 0.617021 (-3390 3410);
PAINT ORANGE (-3390 3410);
FORCEPROP 2 LASTPIN (-3400 3450) $PN AE63
J 0
(-3390 3460);
DISPLAY 0.617021 (-3390 3460);
PAINT ORANGE (-3390 3460);
FORCEPROP 2 LASTPIN (-3400 3500) $PN AE59
J 0
(-3390 3510);
DISPLAY 0.617021 (-3390 3510);
PAINT ORANGE (-3390 3510);
FORCEPROP 2 LASTPIN (-3400 3550) $PN AE56
J 0
(-3390 3560);
DISPLAY 0.617021 (-3390 3560);
PAINT ORANGE (-3390 3560);
FORCEPROP 2 LASTPIN (-3400 3600) $PN AE52
J 0
(-3390 3610);
DISPLAY 0.617021 (-3390 3610);
PAINT ORANGE (-3390 3610);
FORCEPROP 2 LASTPIN (-3400 3650) $PN AE48
J 0
(-3390 3660);
DISPLAY 0.617021 (-3390 3660);
PAINT ORANGE (-3390 3660);
FORCEPROP 2 LASTPIN (-3400 3700) $PN J18
J 0
(-3390 3710);
DISPLAY 0.617021 (-3390 3710);
PAINT ORANGE (-3390 3710);
FORCEPROP 2 LASTPIN (-3400 3750) $PN AE29
J 0
(-3390 3760);
DISPLAY 0.617021 (-3390 3760);
PAINT ORANGE (-3390 3760);
FORCEPROP 2 LASTPIN (-3400 3800) $PN AD68
J 0
(-3390 3810);
DISPLAY 0.617021 (-3390 3810);
PAINT ORANGE (-3390 3810);
FORCEPROP 2 LASTPIN (-3400 3850) $PN AD65
J 0
(-3390 3860);
DISPLAY 0.617021 (-3390 3860);
PAINT ORANGE (-3390 3860);
FORCEPROP 2 LASTPIN (-3400 3900) $PN AD5
J 0
(-3390 3910);
DISPLAY 0.617021 (-3390 3910);
PAINT ORANGE (-3390 3910);
FORCEPROP 2 LASTPIN (-3400 3950) $PN AC7
J 0
(-3390 3960);
DISPLAY 0.617021 (-3390 3960);
PAINT ORANGE (-3390 3960);
FORCEPROP 2 LASTPIN (-3400 4000) $PN AC66
J 0
(-3390 4010);
DISPLAY 0.617021 (-3390 4010);
PAINT ORANGE (-3390 4010);
FORCEPROP 2 LASTPIN (-3400 4050) $PN AC63
J 0
(-3390 4060);
DISPLAY 0.617021 (-3390 4060);
PAINT ORANGE (-3390 4060);
FORCEPROP 2 LASTPIN (-3400 4100) $PN AC59
J 0
(-3390 4110);
DISPLAY 0.617021 (-3390 4110);
PAINT ORANGE (-3390 4110);
FORCEPROP 2 LASTPIN (-3400 4150) $PN AC52
J 0
(-3390 4160);
DISPLAY 0.617021 (-3390 4160);
PAINT ORANGE (-3390 4160);
FORCEPROP 2 LASTPIN (-3400 4250) $PN AC46
J 0
(-3390 4260);
DISPLAY 0.617021 (-3390 4260);
PAINT ORANGE (-3390 4260);
FORCEPROP 2 LASTPIN (-3400 4300) $PN AC43
J 0
(-3390 4310);
DISPLAY 0.617021 (-3390 4310);
PAINT ORANGE (-3390 4310);
FORCEPROP 2 LASTPIN (-3400 4350) $PN AC27
J 0
(-3390 4360);
DISPLAY 0.617021 (-3390 4360);
PAINT ORANGE (-3390 4360);
FORCEPROP 2 LASTPIN (-3400 4400) $PN AD58
J 0
(-3390 4410);
DISPLAY 0.617021 (-3390 4410);
PAINT ORANGE (-3390 4410);
FORCEPROP 2 LASTPIN (-4600 1000) $PN AC22
J 2
(-4610 1010);
DISPLAY 0.617021 (-4610 1010);
PAINT ORANGE (-4610 1010);
FORCEPROP 2 LASTPIN (-4600 1050) $PN AC18
J 2
(-4610 1060);
DISPLAY 0.617021 (-4610 1060);
PAINT ORANGE (-4610 1060);
FORCEPROP 2 LASTPIN (-4600 1100) $PN AC15
J 2
(-4610 1110);
DISPLAY 0.617021 (-4610 1110);
PAINT ORANGE (-4610 1110);
FORCEPROP 2 LASTPIN (-4600 1150) $PN AC11
J 2
(-4610 1160);
DISPLAY 0.617021 (-4610 1160);
PAINT ORANGE (-4610 1160);
FORCEPROP 2 LASTPIN (-4600 1250) $PN AB70
J 2
(-4610 1260);
DISPLAY 0.617021 (-4610 1260);
PAINT ORANGE (-4610 1260);
FORCEPROP 2 LASTPIN (-4600 1450) $PN AA43
J 2
(-4610 1460);
DISPLAY 0.617021 (-4610 1460);
PAINT ORANGE (-4610 1460);
FORCEPROP 2 LASTPIN (-4600 1500) $PN AA27
J 2
(-4610 1510);
DISPLAY 0.617021 (-4610 1510);
PAINT ORANGE (-4610 1510);
FORCEPROP 2 LASTPIN (-4600 1550) $PN AA26
J 2
(-4610 1560);
DISPLAY 0.617021 (-4610 1560);
PAINT ORANGE (-4610 1560);
FORCEPROP 2 LASTPIN (-4600 1600) $PN Y68
J 2
(-4610 1610);
DISPLAY 0.617021 (-4610 1610);
PAINT ORANGE (-4610 1610);
FORCEPROP 2 LASTPIN (-4600 1650) $PN Y63
J 2
(-4610 1660);
DISPLAY 0.617021 (-4610 1660);
PAINT ORANGE (-4610 1660);
FORCEPROP 2 LASTPIN (-4600 1700) $PN Y59
J 2
(-4610 1710);
DISPLAY 0.617021 (-4610 1710);
PAINT ORANGE (-4610 1710);
FORCEPROP 2 LASTPIN (-4600 1750) $PN Y52
J 2
(-4610 1760);
DISPLAY 0.617021 (-4610 1760);
PAINT ORANGE (-4610 1760);
FORCEPROP 2 LASTPIN (-4600 1800) $PN Y5
J 2
(-4610 1810);
DISPLAY 0.617021 (-4610 1810);
PAINT ORANGE (-4610 1810);
FORCEPROP 2 LASTPIN (-4600 1850) $PN Y48
J 2
(-4610 1860);
DISPLAY 0.617021 (-4610 1860);
PAINT ORANGE (-4610 1860);
FORCEPROP 2 LASTPIN (-4600 1900) $PN Y27
J 2
(-4610 1910);
DISPLAY 0.617021 (-4610 1910);
PAINT ORANGE (-4610 1910);
FORCEPROP 2 LASTPIN (-4600 1950) $PN Y22
J 2
(-4610 1960);
DISPLAY 0.617021 (-4610 1960);
PAINT ORANGE (-4610 1960);
FORCEPROP 2 LASTPIN (-4600 2000) $PN W9
J 2
(-4610 2010);
DISPLAY 0.617021 (-4610 2010);
PAINT ORANGE (-4610 2010);
FORCEPROP 2 LASTPIN (-4600 2050) $PN W61
J 2
(-4610 2060);
DISPLAY 0.617021 (-4610 2060);
PAINT ORANGE (-4610 2060);
FORCEPROP 2 LASTPIN (-4600 2100) $PN Y43
J 2
(-4610 2110);
DISPLAY 0.617021 (-4610 2110);
PAINT ORANGE (-4610 2110);
FORCEPROP 2 LASTPIN (-4600 2150) $PN AA50
J 2
(-4610 2160);
DISPLAY 0.617021 (-4610 2160);
PAINT ORANGE (-4610 2160);
FORCEPROP 2 LASTPIN (-4600 2200) $PN W24
J 2
(-4610 2210);
DISPLAY 0.617021 (-4610 2210);
PAINT ORANGE (-4610 2210);
FORCEPROP 2 LASTPIN (-4600 2250) $PN W20
J 2
(-4610 2260);
DISPLAY 0.617021 (-4610 2260);
PAINT ORANGE (-4610 2260);
FORCEPROP 2 LASTPIN (-4600 2300) $PN W17
J 2
(-4610 2310);
DISPLAY 0.617021 (-4610 2310);
PAINT ORANGE (-4610 2310);
FORCEPROP 2 LASTPIN (-4600 2350) $PN W13
J 2
(-4610 2360);
DISPLAY 0.617021 (-4610 2360);
PAINT ORANGE (-4610 2360);
FORCEPROP 2 LASTPIN (-4600 2400) $PN V68
J 2
(-4610 2410);
DISPLAY 0.617021 (-4610 2410);
PAINT ORANGE (-4610 2410);
FORCEPROP 2 LASTPIN (-4600 2450) $PN V66
J 2
(-4610 2460);
DISPLAY 0.617021 (-4610 2460);
PAINT ORANGE (-4610 2460);
FORCEPROP 2 LASTPIN (-4600 2500) $PN W58
J 2
(-4610 2510);
DISPLAY 0.617021 (-4610 2510);
PAINT ORANGE (-4610 2510);
FORCEPROP 2 LASTPIN (-4600 2550) $PN V52
J 2
(-4610 2560);
DISPLAY 0.617021 (-4610 2560);
PAINT ORANGE (-4610 2560);
FORCEPROP 2 LASTPIN (-4600 2600) $PN V5
J 2
(-4610 2610);
DISPLAY 0.617021 (-4610 2610);
PAINT ORANGE (-4610 2610);
FORCEPROP 2 LASTPIN (-4600 2650) $PN V48
J 2
(-4610 2660);
DISPLAY 0.617021 (-4610 2660);
PAINT ORANGE (-4610 2660);
FORCEPROP 2 LASTPIN (-4600 2700) $PN V26
J 2
(-4610 2710);
DISPLAY 0.617021 (-4610 2710);
PAINT ORANGE (-4610 2710);
FORCEPROP 2 LASTPIN (-4600 2750) $PN U58
J 2
(-4610 2760);
DISPLAY 0.617021 (-4610 2760);
PAINT ORANGE (-4610 2760);
FORCEPROP 2 LASTPIN (-4600 2800) $PN AG46
J 2
(-4610 2810);
DISPLAY 0.617021 (-4610 2810);
PAINT ORANGE (-4610 2810);
FORCEPROP 2 LASTPIN (-4600 2850) $PN AF50
J 2
(-4610 2860);
DISPLAY 0.617021 (-4610 2860);
PAINT ORANGE (-4610 2860);
FORCEPROP 2 LASTPIN (-4600 2900) $PN T7
J 2
(-4610 2910);
DISPLAY 0.617021 (-4610 2910);
PAINT ORANGE (-4610 2910);
FORCEPROP 2 LASTPIN (-4600 2950) $PN T66
J 2
(-4610 2960);
DISPLAY 0.617021 (-4610 2960);
PAINT ORANGE (-4610 2960);
FORCEPROP 2 LASTPIN (-4600 3000) $PN T52
J 2
(-4610 3010);
DISPLAY 0.617021 (-4610 3010);
PAINT ORANGE (-4610 3010);
FORCEPROP 2 LASTPIN (-4600 3050) $PN T48
J 2
(-4610 3060);
DISPLAY 0.617021 (-4610 3060);
PAINT ORANGE (-4610 3060);
FORCEPROP 2 LASTPIN (-4600 3100) $PN AJ45
J 2
(-4610 3110);
DISPLAY 0.617021 (-4610 3110);
PAINT ORANGE (-4610 3110);
FORCEPROP 2 LASTPIN (-4600 3150) $PN T40
J 2
(-4610 3160);
DISPLAY 0.617021 (-4610 3160);
PAINT ORANGE (-4610 3160);
FORCEPROP 2 LASTPIN (-4600 3200) $PN T37
J 2
(-4610 3210);
DISPLAY 0.617021 (-4610 3210);
PAINT ORANGE (-4610 3210);
FORCEPROP 2 LASTPIN (-4600 3250) $PN T33
J 2
(-4610 3260);
DISPLAY 0.617021 (-4610 3260);
PAINT ORANGE (-4610 3260);
FORCEPROP 2 LASTPIN (-4600 3300) $PN T29
J 2
(-4610 3310);
DISPLAY 0.617021 (-4610 3310);
PAINT ORANGE (-4610 3310);
FORCEPROP 2 LASTPIN (-4600 3350) $PN T26
J 2
(-4610 3360);
DISPLAY 0.617021 (-4610 3360);
PAINT ORANGE (-4610 3360);
FORCEPROP 2 LASTPIN (-4600 3400) $PN T22
J 2
(-4610 3410);
DISPLAY 0.617021 (-4610 3410);
PAINT ORANGE (-4610 3410);
FORCEPROP 2 LASTPIN (-4600 3450) $PN T18
J 2
(-4610 3460);
DISPLAY 0.617021 (-4610 3460);
PAINT ORANGE (-4610 3460);
FORCEPROP 2 LASTPIN (-4600 3500) $PN T15
J 2
(-4610 3510);
DISPLAY 0.617021 (-4610 3510);
PAINT ORANGE (-4610 3510);
FORCEPROP 2 LASTPIN (-4600 3550) $PN T11
J 2
(-4610 3560);
DISPLAY 0.617021 (-4610 3560);
PAINT ORANGE (-4610 3560);
FORCEPROP 2 LASTPIN (-4600 3600) $PN R68
J 2
(-4610 3610);
DISPLAY 0.617021 (-4610 3610);
PAINT ORANGE (-4610 3610);
FORCEPROP 2 LASTPIN (-4600 3650) $PN R58
J 2
(-4610 3660);
DISPLAY 0.617021 (-4610 3660);
PAINT ORANGE (-4610 3660);
FORCEPROP 2 LASTPIN (-4600 3700) $PN T56
J 2
(-4610 3710);
DISPLAY 0.617021 (-4610 3710);
PAINT ORANGE (-4610 3710);
FORCEPROP 2 LASTPIN (-4600 3750) $PN R54
J 2
(-4610 3760);
DISPLAY 0.617021 (-4610 3760);
PAINT ORANGE (-4610 3760);
FORCEPROP 2 LASTPIN (-4600 3800) $PN R50
J 2
(-4610 3810);
DISPLAY 0.617021 (-4610 3810);
PAINT ORANGE (-4610 3810);
FORCEPROP 2 LASTPIN (-4600 3850) $PN R5
J 2
(-4610 3860);
DISPLAY 0.617021 (-4610 3860);
PAINT ORANGE (-4610 3860);
FORCEPROP 2 LASTPIN (-4600 3900) $PN U42
J 2
(-4610 3910);
DISPLAY 0.617021 (-4610 3910);
PAINT ORANGE (-4610 3910);
FORCEPROP 2 LASTPIN (-4600 3950) $PN R27
J 2
(-4610 3960);
DISPLAY 0.617021 (-4610 3960);
PAINT ORANGE (-4610 3960);
FORCEPROP 2 LASTPIN (-4600 4000) $PN P63
J 2
(-4610 4010);
DISPLAY 0.617021 (-4610 4010);
PAINT ORANGE (-4610 4010);
FORCEPROP 2 LASTPIN (-4600 4050) $PN AE43
J 2
(-4610 4060);
DISPLAY 0.617021 (-4610 4060);
PAINT ORANGE (-4610 4060);
FORCEPROP 2 LASTPIN (-4600 4100) $PN N9
J 2
(-4610 4110);
DISPLAY 0.617021 (-4610 4110);
PAINT ORANGE (-4610 4110);
FORCEPROP 2 LASTPIN (-4600 4150) $PN N68
J 2
(-4610 4160);
DISPLAY 0.617021 (-4610 4160);
PAINT ORANGE (-4610 4160);
FORCEPROP 2 LASTPIN (-4600 4200) $PN R38
J 2
(-4610 4210);
DISPLAY 0.617021 (-4610 4210);
PAINT ORANGE (-4610 4210);
FORCEPROP 2 LASTPIN (-4600 4250) $PN N5
J 2
(-4610 4260);
DISPLAY 0.617021 (-4610 4260);
PAINT ORANGE (-4610 4260);
FORCEPROP 2 LASTPIN (-4600 4300) $PN N46
J 2
(-4610 4310);
DISPLAY 0.617021 (-4610 4310);
PAINT ORANGE (-4610 4310);
FORCEPROP 2 LASTPIN (-4600 4350) $PN N38
J 2
(-4610 4360);
DISPLAY 0.617021 (-4610 4360);
PAINT ORANGE (-4610 4360);
FORCEPROP 2 LASTPIN (-4600 4400) $PN N35
J 2
(-4610 4410);
DISPLAY 0.617021 (-4610 4410);
PAINT ORANGE (-4610 4410);
FORCEPROP 2 LASTPIN (-4600 950) $PN AC45
J 2
(-4610 960);
DISPLAY 0.617021 (-4610 960);
PAINT ORANGE (-4610 960);
FORCEPROP 2 LASTPIN (-4600 1400) $PN AA48
J 2
(-4610 1410);
DISPLAY 0.617021 (-4610 1410);
PAINT ORANGE (-4610 1410);
FORCEPROP 2 LASTPIN (-4600 1350) $PN AB5
J 2
(-4610 1360);
DISPLAY 0.617021 (-4610 1360);
PAINT ORANGE (-4610 1360);
FORCEPROP 2 LASTPIN (-4600 1300) $PN AB68
J 2
(-4610 1310);
DISPLAY 0.617021 (-4610 1310);
PAINT ORANGE (-4610 1310);
FORCEPROP 2 LASTPIN (-3400 1250) $PN AK61
J 0
(-3390 1260);
DISPLAY 0.617021 (-3390 1260);
PAINT ORANGE (-3390 1260);
FORCEPROP 2 LASTPIN (-4600 1200) $PN AB72
J 2
(-4610 1210);
DISPLAY 0.617021 (-4610 1210);
PAINT ORANGE (-4610 1210);
FORCEPROP 2 LASTPIN (-3400 4200) $PN AC48
J 0
(-3390 4210);
DISPLAY 0.617021 (-3390 4210);
PAINT ORANGE (-3390 4210);
FORCEPROP 1 LAST LOCATION U7C1
J 0
(-4500 4725);
DISPLAY 0.617021 (-4500 4725);
PAINT AQUA (-4500 4725);
FORCEPROP 1 LAST PACK_TYPE BGA1
J 0
(-4550 4700);
PAINT SKYBLUE (-4550 4700);
DISPLAY INVISIBLE (-4550 4700);
FORCEPROP 2 LAST SEC_TYPE BGA1
J 0
(-4500 4775);
DISPLAY 1.021277 (-4500 4775);
PAINT ORANGE (-4500 4775);
DISPLAY INVISIBLE (-4500 4775);
FORCEPROP 2 LAST SEC 12
J 0
(-4500 4775);
DISPLAY 0.680851 (-4500 4775);
PAINT MONO (-4500 4775);
DISPLAY INVISIBLE (-4500 4775);
FORCEPROP 2 LAST CDS_LIB mstr_u_proc
J 0
(-4000 2700);
PAINT ORANGE (-4000 2700);
DISPLAY INVISIBLE (-4000 2700);
FORCEPROP 0 LAST BOM_COST SB
J 0
(-4550 4650);
DISPLAY 1.361702 (-4550 4650);
PAINT ORANGE (-4550 4650);
DISPLAY INVISIBLE (-4550 4650);
FORCEPROP 2 LAST CDS_LOCATION U7C1
J 0
(-4500 4725);
DISPLAY 0.617021 (-4500 4725);
PAINT AQUA (-4500 4725);
DISPLAY INVISIBLE (-4500 4725);
FORCEPROP 1 LAST PATH I17
J 0
(-4000 4600);
PAINT GREEN (-4000 4600);
DISPLAY INVISIBLE (-4000 4600);
FORCEPROP 0 LAST ROOM SB
J 0
(-4550 4550);
DISPLAY 1.361702 (-4550 4550);
PAINT ORANGE (-4550 4550);
DISPLAY INVISIBLE (-4550 4550);
FORCEADD GND..1
(-3125 600);
FORCEPROP 3 LASTPIN (-3125 650) SIG_NAME GND\g
J 0
(-3115 660);
DISPLAY 0.659574 (-3115 660);
PAINT MONO (-3115 660);
DISPLAY INVISIBLE (-3115 660);
FORCEPROP 1 LAST VOLTAGE 0.0V
J 0
(-3170 557);
DISPLAY 0.340426 (-3170 557);
PAINT SKYBLUE (-3170 557);
DISPLAY INVISIBLE (-3170 557);
FORCEPROP 1 LAST SIZE 1B
J 0
(-3050 550);
DISPLAY 1.170213 (-3050 550);
PAINT AQUA (-3050 550);
DISPLAY INVISIBLE (-3050 550);
FORCEPROP 2 LAST CDS_LIB mstr_symbols
J 0
(-3125 600);
PAINT ORANGE (-3125 600);
DISPLAY INVISIBLE (-3125 600);
FORCEPROP 1 LAST BODY_TYPE PLUMBING
J 0
(-3170 557);
DISPLAY 0.340426 (-3170 557);
PAINT GREEN (-3170 557);
DISPLAY INVISIBLE (-3170 557);
FORCEPROP 1 LAST PATH I4
J 0
(-3050 600);
DISPLAY 1.170213 (-3050 600);
PAINT AQUA (-3050 600);
DISPLAY INVISIBLE (-3050 600);
FORCEPROP 1 LAST HDL_POWER GND
J 0
(-3125 750);
DISPLAY 1.170213 (-3125 750);
PAINT GREEN (-3125 750);
DISPLAY INVISIBLE (-3125 750);
FORCEADD GND..1
(-4950 600);
FORCEPROP 3 LASTPIN (-4950 650) SIG_NAME GND\g
J 0
(-4940 660);
DISPLAY 0.659574 (-4940 660);
PAINT MONO (-4940 660);
DISPLAY INVISIBLE (-4940 660);
FORCEPROP 1 LAST VOLTAGE 0.0V
J 0
(-4995 557);
DISPLAY 0.340426 (-4995 557);
PAINT SKYBLUE (-4995 557);
DISPLAY INVISIBLE (-4995 557);
FORCEPROP 1 LAST SIZE 1B
J 0
(-4875 550);
DISPLAY 1.170213 (-4875 550);
PAINT AQUA (-4875 550);
DISPLAY INVISIBLE (-4875 550);
FORCEPROP 2 LAST CDS_LIB mstr_symbols
J 0
(-4950 600);
PAINT ORANGE (-4950 600);
DISPLAY INVISIBLE (-4950 600);
FORCEPROP 1 LAST BODY_TYPE PLUMBING
J 0
(-4995 557);
DISPLAY 0.340426 (-4995 557);
PAINT GREEN (-4995 557);
DISPLAY INVISIBLE (-4995 557);
FORCEPROP 1 LAST PATH I6
J 0
(-4875 600);
DISPLAY 1.170213 (-4875 600);
PAINT AQUA (-4875 600);
DISPLAY INVISIBLE (-4875 600);
FORCEPROP 1 LAST HDL_POWER GND
J 0
(-4950 750);
DISPLAY 1.170213 (-4950 750);
PAINT GREEN (-4950 750);
DISPLAY INVISIBLE (-4950 750);
FORCEADD GND..1
(-400 575);
FORCEPROP 3 LASTPIN (-400 625) SIG_NAME GND\g
J 0
(-390 635);
DISPLAY 0.659574 (-390 635);
PAINT MONO (-390 635);
DISPLAY INVISIBLE (-390 635);
FORCEPROP 1 LAST VOLTAGE 0.0V
J 0
(-445 532);
DISPLAY 0.340426 (-445 532);
PAINT SKYBLUE (-445 532);
DISPLAY INVISIBLE (-445 532);
FORCEPROP 2 LAST CDS_LIB mstr_symbols
J 0
(-400 575);
PAINT ORANGE (-400 575);
DISPLAY INVISIBLE (-400 575);
FORCEPROP 1 LAST SIZE 1B
J 0
(-325 525);
DISPLAY 1.170213 (-325 525);
PAINT AQUA (-325 525);
DISPLAY INVISIBLE (-325 525);
FORCEPROP 1 LAST BODY_TYPE PLUMBING
J 0
(-445 532);
DISPLAY 0.340426 (-445 532);
PAINT GREEN (-445 532);
DISPLAY INVISIBLE (-445 532);
FORCEPROP 1 LAST PATH I7
J 0
(-325 575);
DISPLAY 1.170213 (-325 575);
PAINT AQUA (-325 575);
DISPLAY INVISIBLE (-325 575);
FORCEPROP 1 LAST HDL_POWER GND
J 0
(-400 725);
DISPLAY 1.170213 (-400 725);
PAINT GREEN (-400 725);
DISPLAY INVISIBLE (-400 725);
FORCEADD GND..1
(-2550 625);
FORCEPROP 3 LASTPIN (-2550 675) SIG_NAME GND\g
J 0
(-2540 685);
DISPLAY 0.659574 (-2540 685);
PAINT MONO (-2540 685);
DISPLAY INVISIBLE (-2540 685);
FORCEPROP 1 LAST VOLTAGE 0.0V
J 0
(-2595 582);
DISPLAY 0.340426 (-2595 582);
PAINT SKYBLUE (-2595 582);
DISPLAY INVISIBLE (-2595 582);
FORCEPROP 1 LAST SIZE 1B
J 0
(-2475 575);
DISPLAY 1.170213 (-2475 575);
PAINT AQUA (-2475 575);
DISPLAY INVISIBLE (-2475 575);
FORCEPROP 2 LAST CDS_LIB mstr_symbols
J 0
(-2550 625);
PAINT ORANGE (-2550 625);
DISPLAY INVISIBLE (-2550 625);
FORCEPROP 1 LAST BODY_TYPE PLUMBING
J 0
(-2595 582);
DISPLAY 0.340426 (-2595 582);
PAINT GREEN (-2595 582);
DISPLAY INVISIBLE (-2595 582);
FORCEPROP 1 LAST PATH I9
J 0
(-2475 625);
DISPLAY 1.170213 (-2475 625);
PAINT AQUA (-2475 625);
DISPLAY INVISIBLE (-2475 625);
FORCEPROP 1 LAST HDL_POWER GND
J 0
(-2550 775);
DISPLAY 1.170213 (-2550 775);
PAINT GREEN (-2550 775);
DISPLAY INVISIBLE (-2550 775);
FORCEADD INTEL_CORP_BPAGE..1
(2525 0);
FORCEPROP 1 LAST CDS_CON_LAST_MODIFIED Tue Dec 01 11:51:58 2015
J 0
(1100 325);
DISPLAY 1.340426 (1100 325);
PAINT GREEN (1100 325);
DISPLAY INVISIBLE (1100 325);
FORCEPROP 1 LAST CUSTOM_TXT_CDS <CURRENT_DESIGN_SHEET> OF <TOTAL_DESIGN_SHEETS>
J 0
(2025 25);
PAINT GREEN (2025 25);
FORCEPROP 1 LAST CUSTOM_TXT_CDS <CON_LAST_MODIFIED>
J 0
(600 350);
PAINT GREEN (600 350);
FORCEPROP 2 LAST CUSTOM_TXT_CDS <XR_PAGE_TITLE>
J 0
(-5365 5250);
DISPLAY 0.638298 (-5365 5250);
PAINT PINK (-5365 5250);
DISPLAY INVISIBLE (-5365 5250);
FORCEPROP 1 LAST SCH_ADDRESS3 Santa Clara, CA 95052-8119
J 0
(-1450 25);
DISPLAY 0.617021 (-1450 25);
PAINT GREEN (-1450 25);
FORCEPROP 1 LAST SCH_ADDRESS2 P.O. BOX 58119
J 0
(-1450 75);
DISPLAY 0.617021 (-1450 75);
PAINT GREEN (-1450 75);
FORCEPROP 1 LAST SCH_ADDRESS1 2200 Mission College Blvd.
J 0
(-1450 125);
DISPLAY 0.617021 (-1450 125);
PAINT GREEN (-1450 125);
FORCEPROP 1 LAST SCH_TITLE LEWISBURG 11/11 GND
J 0
(-5425 50);
DISPLAY 1.212766 (-5425 50);
PAINT GREEN (-5425 50);
FORCEPROP 1 LAST SCH_NUMBER H4694802
J 0
(1225 150);
DISPLAY 1.212766 (1225 150);
PAINT YELLOW (1225 150);
FORCEPROP 1 LAST SCH_DEPT BESD
J 1
(-1925 100);
DISPLAY 1.212766 (-1925 100);
PAINT YELLOW (-1925 100);
FORCEPROP 1 LAST SCH_REV 2.420
J 0
(2275 150);
DISPLAY 0.978723 (2275 150);
PAINT YELLOW (2275 150);
FORCEPROP 2 LAST PAGE_BORDER TRUE
J 0
(-5365 5250);
DISPLAY 0.851064 (-5365 5250);
PAINT PINK (-5365 5250);
DISPLAY INVISIBLE (-5365 5250);
FORCEPROP 2 LAST CDS_LIB mstr_symbols
J 0
(2525 0);
PAINT ORANGE (2525 0);
DISPLAY INVISIBLE (2525 0);
FORCEPROP 1 LAST COMMENT_BODY TRUE
J 0
(2537 12);
DISPLAY 0.638298 (2537 12);
PAINT GREEN (2537 12);
DISPLAY INVISIBLE (2537 12);
FORCEPROP 2 LAST CDS_XR_PAGE_TITLE CR-124 : @BASEBOARD_FAB2_LIB.BASEBOARD_FAB2(SCH_1):PAGE124
J 0
(-5365 5250);
DISPLAY 0.638298 (-5365 5250);
PAINT PINK (-5365 5250);
DISPLAY INVISIBLE (-5365 5250);
WIRE 16 -1 (225 4400)(600 4400);
WIRE 16 -1 (225 4350)(225 4400);
WIRE 16 -1 (600 4350)(225 4350);
WIRE 16 -1 (225 4350)(225 4300);
WIRE 16 -1 (600 4300)(225 4300);
WIRE 16 -1 (225 4300)(225 4250);
WIRE 16 -1 (600 4250)(225 4250);
WIRE 16 -1 (225 4250)(225 4200);
WIRE 16 -1 (600 4200)(225 4200);
WIRE 16 -1 (225 4200)(225 4150);
WIRE 16 -1 (600 4150)(225 4150);
WIRE 16 -1 (225 4150)(225 4100);
WIRE 16 -1 (600 4100)(225 4100);
WIRE 16 -1 (225 4100)(225 4050);
WIRE 16 -1 (600 4050)(225 4050);
WIRE 16 -1 (225 4000)(225 4050);
WIRE 16 -1 (600 4000)(225 4000);
WIRE 16 -1 (225 4000)(225 3950);
WIRE 16 -1 (600 3950)(225 3950);
WIRE 16 -1 (225 3950)(225 3900);
WIRE 16 -1 (600 3900)(225 3900);
WIRE 16 -1 (225 3900)(225 3850);
WIRE 16 -1 (600 3850)(225 3850);
WIRE 16 -1 (225 3850)(225 3800);
WIRE 16 -1 (600 3800)(225 3800);
WIRE 16 -1 (225 3800)(225 3750);
WIRE 16 -1 (600 3750)(225 3750);
WIRE 16 -1 (225 3750)(225 3700);
WIRE 16 -1 (600 3700)(225 3700);
WIRE 16 -1 (225 3700)(225 3650);
WIRE 16 -1 (600 3650)(225 3650);
WIRE 16 -1 (225 3600)(225 3650);
WIRE 16 -1 (600 3600)(225 3600);
WIRE 16 -1 (225 3600)(225 3550);
WIRE 16 -1 (600 3550)(225 3550);
WIRE 16 -1 (225 3550)(225 3500);
WIRE 16 -1 (600 3500)(225 3500);
WIRE 16 -1 (225 3500)(225 3450);
WIRE 16 -1 (600 3450)(225 3450);
WIRE 16 -1 (225 3450)(225 3400);
WIRE 16 -1 (600 3400)(225 3400);
WIRE 16 -1 (225 3400)(225 3350);
WIRE 16 -1 (600 3350)(225 3350);
WIRE 16 -1 (225 3350)(225 3300);
WIRE 16 -1 (600 3300)(225 3300);
WIRE 16 -1 (225 3300)(225 3250);
WIRE 16 -1 (600 3250)(225 3250);
WIRE 16 -1 (225 3250)(225 3200);
WIRE 16 -1 (600 3200)(225 3200);
WIRE 16 -1 (225 3200)(225 3150);
WIRE 16 -1 (600 3150)(225 3150);
WIRE 16 -1 (225 3150)(225 3100);
WIRE 16 -1 (600 3100)(225 3100);
WIRE 16 -1 (225 3100)(225 3050);
WIRE 16 -1 (600 3050)(225 3050);
WIRE 16 -1 (225 3050)(225 3000);
WIRE 16 -1 (600 3000)(225 3000);
WIRE 16 -1 (225 3000)(225 2950);
WIRE 16 -1 (600 2950)(225 2950);
WIRE 16 -1 (225 2950)(225 2900);
WIRE 16 -1 (600 2900)(225 2900);
WIRE 16 -1 (225 2900)(225 2850);
WIRE 16 -1 (600 2850)(225 2850);
WIRE 16 -1 (225 2850)(225 2800);
WIRE 16 -1 (600 2800)(225 2800);
WIRE 16 -1 (225 2800)(225 2750);
WIRE 16 -1 (600 2750)(225 2750);
WIRE 16 -1 (225 2750)(225 2700);
WIRE 16 -1 (600 2700)(225 2700);
WIRE 16 -1 (225 2700)(225 2650);
WIRE 16 -1 (600 2650)(225 2650);
WIRE 16 -1 (225 2650)(225 2600);
WIRE 16 -1 (600 2600)(225 2600);
WIRE 16 -1 (225 2600)(225 2550);
WIRE 16 -1 (600 2550)(225 2550);
WIRE 16 -1 (225 2550)(225 2500);
WIRE 16 -1 (600 2500)(225 2500);
WIRE 16 -1 (225 2500)(225 2450);
WIRE 16 -1 (600 2450)(225 2450);
WIRE 16 -1 (225 2450)(225 2400);
WIRE 16 -1 (600 2400)(225 2400);
WIRE 16 -1 (225 2400)(225 2350);
WIRE 16 -1 (600 2350)(225 2350);
WIRE 16 -1 (225 2350)(225 2300);
WIRE 16 -1 (600 2300)(225 2300);
WIRE 16 -1 (225 2300)(225 2250);
WIRE 16 -1 (600 2250)(225 2250);
WIRE 16 -1 (225 2250)(225 2200);
WIRE 16 -1 (600 2200)(225 2200);
WIRE 16 -1 (225 2200)(225 2150);
WIRE 16 -1 (600 2150)(225 2150);
WIRE 16 -1 (225 2150)(225 2100);
WIRE 16 -1 (600 2100)(225 2100);
WIRE 16 -1 (225 2100)(225 2050);
WIRE 16 -1 (600 2050)(225 2050);
WIRE 16 -1 (225 2000)(225 2050);
WIRE 16 -1 (600 2000)(225 2000);
WIRE 16 -1 (225 2000)(225 1950);
WIRE 16 -1 (600 1950)(225 1950);
WIRE 16 -1 (225 1950)(225 1900);
WIRE 16 -1 (600 1900)(225 1900);
WIRE 16 -1 (225 1900)(225 1850);
WIRE 16 -1 (600 1850)(225 1850);
WIRE 16 -1 (225 1850)(225 1800);
WIRE 16 -1 (600 1800)(225 1800);
WIRE 16 -1 (225 1800)(225 1750);
WIRE 16 -1 (600 1750)(225 1750);
WIRE 16 -1 (225 1750)(225 1700);
WIRE 16 -1 (600 1700)(225 1700);
WIRE 16 -1 (225 1650)(225 1700);
WIRE 16 -1 (600 1650)(225 1650);
WIRE 16 -1 (225 1650)(225 1600);
WIRE 16 -1 (600 1600)(225 1600);
WIRE 16 -1 (225 1600)(225 1550);
WIRE 16 -1 (600 1550)(225 1550);
WIRE 16 -1 (225 1550)(225 1500);
WIRE 16 -1 (600 1500)(225 1500);
WIRE 16 -1 (225 1500)(225 1450);
WIRE 16 -1 (600 1450)(225 1450);
WIRE 16 -1 (225 1450)(225 1400);
WIRE 16 -1 (600 1400)(225 1400);
WIRE 16 -1 (225 1400)(225 1350);
WIRE 16 -1 (600 1350)(225 1350);
WIRE 16 -1 (225 1300)(225 1350);
WIRE 16 -1 (600 1300)(225 1300);
WIRE 16 -1 (225 1300)(225 1250);
WIRE 16 -1 (600 1250)(225 1250);
WIRE 16 -1 (225 1250)(225 1200);
WIRE 16 -1 (600 1200)(225 1200);
WIRE 16 -1 (225 1200)(225 1150);
WIRE 16 -1 (600 1150)(225 1150);
WIRE 16 -1 (225 1150)(225 1100);
WIRE 16 -1 (600 1100)(225 1100);
WIRE 16 -1 (225 1100)(225 1050);
WIRE 16 -1 (600 1050)(225 1050);
WIRE 16 -1 (225 1050)(225 1000);
WIRE 16 -1 (600 1000)(225 1000);
WIRE 16 -1 (225 950)(225 1000);
WIRE 16 -1 (225 950)(600 950);
WIRE 16 -1 (225 875)(225 950);
WIRE 16 -1 (1800 4400)(2200 4400);
WIRE 16 -1 (2200 4350)(2200 4400);
WIRE 16 -1 (1800 4350)(2200 4350);
WIRE 16 -1 (2200 4300)(2200 4350);
WIRE 16 -1 (1800 4300)(2200 4300);
WIRE 16 -1 (2200 4250)(2200 4300);
WIRE 16 -1 (1800 4250)(2200 4250);
WIRE 16 -1 (2200 4200)(2200 4250);
WIRE 16 -1 (1800 4200)(2200 4200);
WIRE 16 -1 (2200 4125)(2200 4200);
WIRE 16 -1 (-3125 4350)(-3125 4400);
WIRE 16 -1 (-3400 4350)(-3125 4350);
WIRE 16 -1 (-3125 4300)(-3125 4350);
WIRE 16 -1 (-3125 4400)(-3400 4400);
WIRE 16 -1 (-3400 4300)(-3125 4300);
WIRE 16 -1 (-3125 4250)(-3125 4300);
WIRE 16 -1 (-3400 4250)(-3125 4250);
WIRE 16 -1 (-3125 4200)(-3125 4250);
WIRE 16 -1 (-3400 4200)(-3125 4200);
WIRE 16 -1 (-3125 4150)(-3125 4200);
WIRE 16 -1 (-3400 4150)(-3125 4150);
WIRE 16 -1 (-3125 4100)(-3125 4150);
WIRE 16 -1 (-3400 4100)(-3125 4100);
WIRE 16 -1 (-3125 4050)(-3125 4100);
WIRE 16 -1 (-3400 4050)(-3125 4050);
WIRE 16 -1 (-3125 4000)(-3125 4050);
WIRE 16 -1 (-3400 4000)(-3125 4000);
WIRE 16 -1 (-3125 3950)(-3125 4000);
WIRE 16 -1 (-3400 3950)(-3125 3950);
WIRE 16 -1 (-3125 3900)(-3125 3950);
WIRE 16 -1 (-3400 3900)(-3125 3900);
WIRE 16 -1 (-3125 3850)(-3125 3900);
WIRE 16 -1 (-3400 3850)(-3125 3850);
WIRE 16 -1 (-3125 3800)(-3125 3850);
WIRE 16 -1 (-3400 3800)(-3125 3800);
WIRE 16 -1 (-3125 3750)(-3125 3800);
WIRE 16 -1 (-3400 3750)(-3125 3750);
WIRE 16 -1 (-3125 3700)(-3125 3750);
WIRE 16 -1 (-3400 3700)(-3125 3700);
WIRE 16 -1 (-3125 3650)(-3125 3700);
WIRE 16 -1 (-3400 3650)(-3125 3650);
WIRE 16 -1 (-3125 3600)(-3125 3650);
WIRE 16 -1 (-3400 3600)(-3125 3600);
WIRE 16 -1 (-3125 3550)(-3125 3600);
WIRE 16 -1 (-3400 3550)(-3125 3550);
WIRE 16 -1 (-3125 3500)(-3125 3550);
WIRE 16 -1 (-3400 3500)(-3125 3500);
WIRE 16 -1 (-3125 3450)(-3125 3500);
WIRE 16 -1 (-3400 3450)(-3125 3450);
WIRE 16 -1 (-3125 3400)(-3125 3450);
WIRE 16 -1 (-3400 3400)(-3125 3400);
WIRE 16 -1 (-3125 3350)(-3125 3400);
WIRE 16 -1 (-3400 3350)(-3125 3350);
WIRE 16 -1 (-3125 3300)(-3125 3350);
WIRE 16 -1 (-3400 3300)(-3125 3300);
WIRE 16 -1 (-3125 3250)(-3125 3300);
WIRE 16 -1 (-3400 3250)(-3125 3250);
WIRE 16 -1 (-3125 3200)(-3125 3250);
WIRE 16 -1 (-3400 3200)(-3125 3200);
WIRE 16 -1 (-3125 3150)(-3125 3200);
WIRE 16 -1 (-3400 3150)(-3125 3150);
WIRE 16 -1 (-3125 3100)(-3125 3150);
WIRE 16 -1 (-3400 3100)(-3125 3100);
WIRE 16 -1 (-3125 3050)(-3125 3100);
WIRE 16 -1 (-3400 3050)(-3125 3050);
WIRE 16 -1 (-3125 3000)(-3125 3050);
WIRE 16 -1 (-3400 3000)(-3125 3000);
WIRE 16 -1 (-3125 2950)(-3125 3000);
WIRE 16 -1 (-3400 2950)(-3125 2950);
WIRE 16 -1 (-3125 2900)(-3125 2950);
WIRE 16 -1 (-3400 2900)(-3125 2900);
WIRE 16 -1 (-3125 2850)(-3125 2900);
WIRE 16 -1 (-3400 2850)(-3125 2850);
WIRE 16 -1 (-3125 2800)(-3125 2850);
WIRE 16 -1 (-3400 2800)(-3125 2800);
WIRE 16 -1 (-3125 2750)(-3125 2800);
WIRE 16 -1 (-3400 2750)(-3125 2750);
WIRE 16 -1 (-3125 2700)(-3125 2750);
WIRE 16 -1 (-3400 2700)(-3125 2700);
WIRE 16 -1 (-3125 2650)(-3125 2700);
WIRE 16 -1 (-3400 2650)(-3125 2650);
WIRE 16 -1 (-3125 2600)(-3125 2650);
WIRE 16 -1 (-3400 2600)(-3125 2600);
WIRE 16 -1 (-3125 2550)(-3125 2600);
WIRE 16 -1 (-3400 2550)(-3125 2550);
WIRE 16 -1 (-3125 2500)(-3125 2550);
WIRE 16 -1 (-3400 2500)(-3125 2500);
WIRE 16 -1 (-3125 2450)(-3125 2500);
WIRE 16 -1 (-3400 2450)(-3125 2450);
WIRE 16 -1 (-3125 2400)(-3125 2450);
WIRE 16 -1 (-3400 2400)(-3125 2400);
WIRE 16 -1 (-3125 2350)(-3125 2400);
WIRE 16 -1 (-3400 2350)(-3125 2350);
WIRE 16 -1 (-3125 2300)(-3125 2350);
WIRE 16 -1 (-3400 2300)(-3125 2300);
WIRE 16 -1 (-3125 2250)(-3125 2300);
WIRE 16 -1 (-3400 2250)(-3125 2250);
WIRE 16 -1 (-3125 2200)(-3125 2250);
WIRE 16 -1 (-3400 2200)(-3125 2200);
WIRE 16 -1 (-3125 2150)(-3125 2200);
WIRE 16 -1 (-3400 2150)(-3125 2150);
WIRE 16 -1 (-3125 2100)(-3125 2150);
WIRE 16 -1 (-3400 2100)(-3125 2100);
WIRE 16 -1 (-3125 2050)(-3125 2100);
WIRE 16 -1 (-3400 2050)(-3125 2050);
WIRE 16 -1 (-3125 2000)(-3125 2050);
WIRE 16 -1 (-3400 2000)(-3125 2000);
WIRE 16 -1 (-3125 1950)(-3125 2000);
WIRE 16 -1 (-3400 1950)(-3125 1950);
WIRE 16 -1 (-3125 1900)(-3125 1950);
WIRE 16 -1 (-3400 1900)(-3125 1900);
WIRE 16 -1 (-3125 1850)(-3125 1900);
WIRE 16 -1 (-3400 1850)(-3125 1850);
WIRE 16 -1 (-3125 1800)(-3125 1850);
WIRE 16 -1 (-3400 1800)(-3125 1800);
WIRE 16 -1 (-3125 1750)(-3125 1800);
WIRE 16 -1 (-3400 1750)(-3125 1750);
WIRE 16 -1 (-3125 1700)(-3125 1750);
WIRE 16 -1 (-3400 1700)(-3125 1700);
WIRE 16 -1 (-3125 1650)(-3125 1700);
WIRE 16 -1 (-3400 1650)(-3125 1650);
WIRE 16 -1 (-3125 1600)(-3125 1650);
WIRE 16 -1 (-3400 1600)(-3125 1600);
WIRE 16 -1 (-3125 1550)(-3125 1600);
WIRE 16 -1 (-3400 1550)(-3125 1550);
WIRE 16 -1 (-3125 1500)(-3125 1550);
WIRE 16 -1 (-3400 1500)(-3125 1500);
WIRE 16 -1 (-3125 1450)(-3125 1500);
WIRE 16 -1 (-3400 1450)(-3125 1450);
WIRE 16 -1 (-3125 1400)(-3125 1450);
WIRE 16 -1 (-3400 1400)(-3125 1400);
WIRE 16 -1 (-3125 1400)(-3125 1350);
WIRE 16 -1 (-3400 1350)(-3125 1350);
WIRE 16 -1 (-3125 1350)(-3125 1300);
WIRE 16 -1 (-3400 1300)(-3125 1300);
WIRE 16 -1 (-3125 1250)(-3125 1300);
WIRE 16 -1 (-3400 1250)(-3125 1250);
WIRE 16 -1 (-3125 1200)(-3125 1250);
WIRE 16 -1 (-3400 1200)(-3125 1200);
WIRE 16 -1 (-3125 1150)(-3125 1200);
WIRE 16 -1 (-3400 1150)(-3125 1150);
WIRE 16 -1 (-3125 1100)(-3125 1150);
WIRE 16 -1 (-3400 1100)(-3125 1100);
WIRE 16 -1 (-3125 1050)(-3125 1100);
WIRE 16 -1 (-3400 1050)(-3125 1050);
WIRE 16 -1 (-3125 1000)(-3125 1050);
WIRE 16 -1 (-3400 1000)(-3125 1000);
WIRE 16 -1 (-3125 950)(-3125 1000);
WIRE 16 -1 (-3400 950)(-3125 950);
WIRE 16 -1 (-3125 650)(-3125 950);
WIRE 16 -1 (-4950 4400)(-4600 4400);
WIRE 16 -1 (-4950 4350)(-4950 4400);
WIRE 16 -1 (-4600 4350)(-4950 4350);
WIRE 16 -1 (-4950 4300)(-4950 4350);
WIRE 16 -1 (-4600 4300)(-4950 4300);
WIRE 16 -1 (-4950 4250)(-4950 4300);
WIRE 16 -1 (-4600 4250)(-4950 4250);
WIRE 16 -1 (-4950 4200)(-4950 4250);
WIRE 16 -1 (-4600 4200)(-4950 4200);
WIRE 16 -1 (-4950 4150)(-4950 4200);
WIRE 16 -1 (-4600 4150)(-4950 4150);
WIRE 16 -1 (-4950 4150)(-4950 4100);
WIRE 16 -1 (-4600 4100)(-4950 4100);
WIRE 16 -1 (-4950 4100)(-4950 4050);
WIRE 16 -1 (-4600 4050)(-4950 4050);
WIRE 16 -1 (-4950 4050)(-4950 4000);
WIRE 16 -1 (-4600 4000)(-4950 4000);
WIRE 16 -1 (-4950 4000)(-4950 3950);
WIRE 16 -1 (-4600 3950)(-4950 3950);
WIRE 16 -1 (-4950 3950)(-4950 3900);
WIRE 16 -1 (-4600 3900)(-4950 3900);
WIRE 16 -1 (-4950 3900)(-4950 3850);
WIRE 16 -1 (-4600 3850)(-4950 3850);
WIRE 16 -1 (-4950 3850)(-4950 3800);
WIRE 16 -1 (-4600 3800)(-4950 3800);
WIRE 16 -1 (-4950 3800)(-4950 3750);
WIRE 16 -1 (-4600 3750)(-4950 3750);
WIRE 16 -1 (-4950 3750)(-4950 3700);
WIRE 16 -1 (-4600 3700)(-4950 3700);
WIRE 16 -1 (-4950 3700)(-4950 3650);
WIRE 16 -1 (-4600 3650)(-4950 3650);
WIRE 16 -1 (-4950 3650)(-4950 3600);
WIRE 16 -1 (-4600 3600)(-4950 3600);
WIRE 16 -1 (-4950 3600)(-4950 3550);
WIRE 16 -1 (-4600 3550)(-4950 3550);
WIRE 16 -1 (-4950 3550)(-4950 3500);
WIRE 16 -1 (-4600 3500)(-4950 3500);
WIRE 16 -1 (-4950 3500)(-4950 3450);
WIRE 16 -1 (-4600 3450)(-4950 3450);
WIRE 16 -1 (-4950 3450)(-4950 3400);
WIRE 16 -1 (-4600 3400)(-4950 3400);
WIRE 16 -1 (-4950 3400)(-4950 3350);
WIRE 16 -1 (-4600 3350)(-4950 3350);
WIRE 16 -1 (-4950 3350)(-4950 3300);
WIRE 16 -1 (-4600 3300)(-4950 3300);
WIRE 16 -1 (-4950 3300)(-4950 3250);
WIRE 16 -1 (-4600 3250)(-4950 3250);
WIRE 16 -1 (-4950 3250)(-4950 3200);
WIRE 16 -1 (-4600 3200)(-4950 3200);
WIRE 16 -1 (-4950 3200)(-4950 3150);
WIRE 16 -1 (-4600 3150)(-4950 3150);
WIRE 16 -1 (-4950 3150)(-4950 3100);
WIRE 16 -1 (-4600 3100)(-4950 3100);
WIRE 16 -1 (-4950 3100)(-4950 3050);
WIRE 16 -1 (-4600 3050)(-4950 3050);
WIRE 16 -1 (-4950 3050)(-4950 3000);
WIRE 16 -1 (-4600 3000)(-4950 3000);
WIRE 16 -1 (-4950 3000)(-4950 2950);
WIRE 16 -1 (-4600 2950)(-4950 2950);
WIRE 16 -1 (-4950 2950)(-4950 2900);
WIRE 16 -1 (-4600 2900)(-4950 2900);
WIRE 16 -1 (-4950 2900)(-4950 2850);
WIRE 16 -1 (-4600 2850)(-4950 2850);
WIRE 16 -1 (-4950 2850)(-4950 2800);
WIRE 16 -1 (-4600 2800)(-4950 2800);
WIRE 16 -1 (-4950 2800)(-4950 2750);
WIRE 16 -1 (-4600 2750)(-4950 2750);
WIRE 16 -1 (-4950 2750)(-4950 2700);
WIRE 16 -1 (-4600 2700)(-4950 2700);
WIRE 16 -1 (-4950 2700)(-4950 2650);
WIRE 16 -1 (-4600 2650)(-4950 2650);
WIRE 16 -1 (-4950 2650)(-4950 2600);
WIRE 16 -1 (-4600 2600)(-4950 2600);
WIRE 16 -1 (-4950 2600)(-4950 2550);
WIRE 16 -1 (-4600 2550)(-4950 2550);
WIRE 16 -1 (-4950 2550)(-4950 2500);
WIRE 16 -1 (-4600 2500)(-4950 2500);
WIRE 16 -1 (-4950 2500)(-4950 2450);
WIRE 16 -1 (-4600 2450)(-4950 2450);
WIRE 16 -1 (-4950 2450)(-4950 2400);
WIRE 16 -1 (-4600 2400)(-4950 2400);
WIRE 16 -1 (-4950 2400)(-4950 2350);
WIRE 16 -1 (-4600 2350)(-4950 2350);
WIRE 16 -1 (-4950 2350)(-4950 2300);
WIRE 16 -1 (-4600 2300)(-4950 2300);
WIRE 16 -1 (-4950 2300)(-4950 2250);
WIRE 16 -1 (-4600 2250)(-4950 2250);
WIRE 16 -1 (-4950 2250)(-4950 2200);
WIRE 16 -1 (-4600 2200)(-4950 2200);
WIRE 16 -1 (-4950 2200)(-4950 2150);
WIRE 16 -1 (-4600 2150)(-4950 2150);
WIRE 16 -1 (-4950 2150)(-4950 2100);
WIRE 16 -1 (-4600 2100)(-4950 2100);
WIRE 16 -1 (-4950 2100)(-4950 2050);
WIRE 16 -1 (-4600 2050)(-4950 2050);
WIRE 16 -1 (-4950 2050)(-4950 2000);
WIRE 16 -1 (-4600 2000)(-4950 2000);
WIRE 16 -1 (-4950 2000)(-4950 1950);
WIRE 16 -1 (-4600 1950)(-4950 1950);
WIRE 16 -1 (-4950 1950)(-4950 1900);
WIRE 16 -1 (-4600 1900)(-4950 1900);
WIRE 16 -1 (-4950 1900)(-4950 1850);
WIRE 16 -1 (-4600 1850)(-4950 1850);
WIRE 16 -1 (-4950 1850)(-4950 1800);
WIRE 16 -1 (-4600 1800)(-4950 1800);
WIRE 16 -1 (-4950 1800)(-4950 1750);
WIRE 16 -1 (-4600 1750)(-4950 1750);
WIRE 16 -1 (-4950 1750)(-4950 1700);
WIRE 16 -1 (-4600 1700)(-4950 1700);
WIRE 16 -1 (-4950 1700)(-4950 1650);
WIRE 16 -1 (-4600 1650)(-4950 1650);
WIRE 16 -1 (-4950 1650)(-4950 1600);
WIRE 16 -1 (-4600 1600)(-4950 1600);
WIRE 16 -1 (-4950 1600)(-4950 1550);
WIRE 16 -1 (-4600 1550)(-4950 1550);
WIRE 16 -1 (-4950 1550)(-4950 1500);
WIRE 16 -1 (-4600 1500)(-4950 1500);
WIRE 16 -1 (-4950 1500)(-4950 1450);
WIRE 16 -1 (-4600 1450)(-4950 1450);
WIRE 16 -1 (-4950 1450)(-4950 1400);
WIRE 16 -1 (-4600 1400)(-4950 1400);
WIRE 16 -1 (-4950 1400)(-4950 1350);
WIRE 16 -1 (-4600 1350)(-4950 1350);
WIRE 16 -1 (-4950 1350)(-4950 1300);
WIRE 16 -1 (-4600 1300)(-4950 1300);
WIRE 16 -1 (-4950 1300)(-4950 1250);
WIRE 16 -1 (-4600 1250)(-4950 1250);
WIRE 16 -1 (-4950 1250)(-4950 1200);
WIRE 16 -1 (-4600 1200)(-4950 1200);
WIRE 16 -1 (-4950 1200)(-4950 1150);
WIRE 16 -1 (-4600 1150)(-4950 1150);
WIRE 16 -1 (-4950 1150)(-4950 1100);
WIRE 16 -1 (-4600 1100)(-4950 1100);
WIRE 16 -1 (-4950 1100)(-4950 1050);
WIRE 16 -1 (-4600 1050)(-4950 1050);
WIRE 16 -1 (-4950 1050)(-4950 1000);
WIRE 16 -1 (-4950 1000)(-4600 1000);
WIRE 16 -1 (-4950 1000)(-4950 950);
WIRE 16 -1 (-4950 950)(-4600 950);
WIRE 16 -1 (-4950 650)(-4950 950);
WIRE 16 -1 (-400 4375)(-400 4425);
WIRE 16 -1 (-875 4375)(-400 4375);
WIRE 16 -1 (-400 4325)(-400 4375);
WIRE 16 -1 (-400 4425)(-875 4425);
WIRE 16 -1 (-875 4325)(-400 4325);
WIRE 16 -1 (-400 4275)(-400 4325);
WIRE 16 -1 (-875 4275)(-400 4275);
WIRE 16 -1 (-400 4225)(-400 4275);
WIRE 16 -1 (-875 4225)(-400 4225);
WIRE 16 -1 (-400 4175)(-400 4225);
WIRE 16 -1 (-875 4175)(-400 4175);
WIRE 16 -1 (-400 4125)(-400 4175);
WIRE 16 -1 (-875 4125)(-400 4125);
WIRE 16 -1 (-400 4075)(-400 4125);
WIRE 16 -1 (-875 4075)(-400 4075);
WIRE 16 -1 (-400 4025)(-400 4075);
WIRE 16 -1 (-875 4025)(-400 4025);
WIRE 16 -1 (-400 3975)(-400 4025);
WIRE 16 -1 (-875 3975)(-400 3975);
WIRE 16 -1 (-400 3925)(-400 3975);
WIRE 16 -1 (-875 3925)(-400 3925);
WIRE 16 -1 (-400 3875)(-400 3925);
WIRE 16 -1 (-875 3875)(-400 3875);
WIRE 16 -1 (-400 3825)(-400 3875);
WIRE 16 -1 (-875 3825)(-400 3825);
WIRE 16 -1 (-400 3775)(-400 3825);
WIRE 16 -1 (-875 3775)(-400 3775);
WIRE 16 -1 (-400 3725)(-400 3775);
WIRE 16 -1 (-875 3725)(-400 3725);
WIRE 16 -1 (-400 3675)(-400 3725);
WIRE 16 -1 (-875 3675)(-400 3675);
WIRE 16 -1 (-400 3625)(-400 3675);
WIRE 16 -1 (-875 3625)(-400 3625);
WIRE 16 -1 (-400 3575)(-400 3625);
WIRE 16 -1 (-875 3575)(-400 3575);
WIRE 16 -1 (-400 3525)(-400 3575);
WIRE 16 -1 (-875 3525)(-400 3525);
WIRE 16 -1 (-400 3475)(-400 3525);
WIRE 16 -1 (-875 3475)(-400 3475);
WIRE 16 -1 (-400 3425)(-400 3475);
WIRE 16 -1 (-875 3425)(-400 3425);
WIRE 16 -1 (-400 3375)(-400 3425);
WIRE 16 -1 (-875 3375)(-400 3375);
WIRE 16 -1 (-400 3325)(-400 3375);
WIRE 16 -1 (-875 3325)(-400 3325);
WIRE 16 -1 (-400 3275)(-400 3325);
WIRE 16 -1 (-875 3275)(-400 3275);
WIRE 16 -1 (-400 3225)(-400 3275);
WIRE 16 -1 (-875 3225)(-400 3225);
WIRE 16 -1 (-400 3175)(-400 3225);
WIRE 16 -1 (-875 3175)(-400 3175);
WIRE 16 -1 (-400 3125)(-400 3175);
WIRE 16 -1 (-875 3125)(-400 3125);
WIRE 16 -1 (-400 3075)(-400 3125);
WIRE 16 -1 (-875 3075)(-400 3075);
WIRE 16 -1 (-400 3025)(-400 3075);
WIRE 16 -1 (-875 3025)(-400 3025);
WIRE 16 -1 (-400 2975)(-400 3025);
WIRE 16 -1 (-875 2975)(-400 2975);
WIRE 16 -1 (-400 2925)(-400 2975);
WIRE 16 -1 (-875 2925)(-400 2925);
WIRE 16 -1 (-400 2875)(-400 2925);
WIRE 16 -1 (-875 2875)(-400 2875);
WIRE 16 -1 (-400 2875)(-400 2825);
WIRE 16 -1 (-875 2825)(-400 2825);
WIRE 16 -1 (-400 2825)(-400 2775);
WIRE 16 -1 (-875 2775)(-400 2775);
WIRE 16 -1 (-400 2775)(-400 2725);
WIRE 16 -1 (-875 2725)(-400 2725);
WIRE 16 -1 (-400 2725)(-400 2675);
WIRE 16 -1 (-875 2675)(-400 2675);
WIRE 16 -1 (-400 2675)(-400 2625);
WIRE 16 -1 (-875 2625)(-400 2625);
WIRE 16 -1 (-400 2625)(-400 2575);
WIRE 16 -1 (-875 2575)(-400 2575);
WIRE 16 -1 (-400 2575)(-400 2525);
WIRE 16 -1 (-875 2525)(-400 2525);
WIRE 16 -1 (-400 2525)(-400 2475);
WIRE 16 -1 (-875 2475)(-400 2475);
WIRE 16 -1 (-400 2475)(-400 2425);
WIRE 16 -1 (-875 2425)(-400 2425);
WIRE 16 -1 (-400 2425)(-400 2375);
WIRE 16 -1 (-875 2375)(-400 2375);
WIRE 16 -1 (-400 2375)(-400 2325);
WIRE 16 -1 (-875 2325)(-400 2325);
WIRE 16 -1 (-400 2325)(-400 2275);
WIRE 16 -1 (-875 2275)(-400 2275);
WIRE 16 -1 (-400 2275)(-400 2225);
WIRE 16 -1 (-875 2225)(-400 2225);
WIRE 16 -1 (-400 2225)(-400 2175);
WIRE 16 -1 (-875 2175)(-400 2175);
WIRE 16 -1 (-400 2175)(-400 2125);
WIRE 16 -1 (-875 2125)(-400 2125);
WIRE 16 -1 (-400 2125)(-400 2075);
WIRE 16 -1 (-875 2075)(-400 2075);
WIRE 16 -1 (-400 2075)(-400 2025);
WIRE 16 -1 (-875 2025)(-400 2025);
WIRE 16 -1 (-400 2025)(-400 1975);
WIRE 16 -1 (-875 1975)(-400 1975);
WIRE 16 -1 (-400 1925)(-400 1975);
WIRE 16 -1 (-875 1925)(-400 1925);
WIRE 16 -1 (-400 1925)(-400 1875);
WIRE 16 -1 (-875 1875)(-400 1875);
WIRE 16 -1 (-400 1875)(-400 1825);
WIRE 16 -1 (-875 1825)(-400 1825);
WIRE 16 -1 (-400 1825)(-400 1775);
WIRE 16 -1 (-875 1775)(-400 1775);
WIRE 16 -1 (-400 1775)(-400 1725);
WIRE 16 -1 (-875 1725)(-400 1725);
WIRE 16 -1 (-400 1725)(-400 1675);
WIRE 16 -1 (-875 1675)(-400 1675);
WIRE 16 -1 (-400 1675)(-400 1625);
WIRE 16 -1 (-875 1625)(-400 1625);
WIRE 16 -1 (-400 1625)(-400 1575);
WIRE 16 -1 (-875 1575)(-400 1575);
WIRE 16 -1 (-400 1575)(-400 1525);
WIRE 16 -1 (-875 1525)(-400 1525);
WIRE 16 -1 (-400 1525)(-400 1475);
WIRE 16 -1 (-875 1475)(-400 1475);
WIRE 16 -1 (-400 1475)(-400 1425);
WIRE 16 -1 (-875 1425)(-400 1425);
WIRE 16 -1 (-400 1425)(-400 1375);
WIRE 16 -1 (-875 1375)(-400 1375);
WIRE 16 -1 (-400 1375)(-400 1325);
WIRE 16 -1 (-875 1325)(-400 1325);
WIRE 16 -1 (-400 1325)(-400 1275);
WIRE 16 -1 (-875 1275)(-400 1275);
WIRE 16 -1 (-400 1275)(-400 1225);
WIRE 16 -1 (-875 1225)(-400 1225);
WIRE 16 -1 (-400 1225)(-400 1175);
WIRE 16 -1 (-875 1175)(-400 1175);
WIRE 16 -1 (-400 1175)(-400 1125);
WIRE 16 -1 (-875 1125)(-400 1125);
WIRE 16 -1 (-400 1125)(-400 1075);
WIRE 16 -1 (-875 1075)(-400 1075);
WIRE 16 -1 (-400 1075)(-400 1025);
WIRE 16 -1 (-875 1025)(-400 1025);
WIRE 16 -1 (-400 1025)(-400 975);
WIRE 16 -1 (-875 975)(-400 975);
WIRE 16 -1 (-400 625)(-400 975);
WIRE 16 -1 (-2550 4425)(-2075 4425);
WIRE 16 -1 (-2550 4375)(-2550 4425);
WIRE 16 -1 (-2075 4375)(-2550 4375);
WIRE 16 -1 (-2550 4375)(-2550 4325);
WIRE 16 -1 (-2075 4325)(-2550 4325);
WIRE 16 -1 (-2550 4325)(-2550 4275);
WIRE 16 -1 (-2075 4275)(-2550 4275);
WIRE 16 -1 (-2550 4275)(-2550 4225);
WIRE 16 -1 (-2075 4225)(-2550 4225);
WIRE 16 -1 (-2550 4225)(-2550 4175);
WIRE 16 -1 (-2075 4175)(-2550 4175);
WIRE 16 -1 (-2550 4175)(-2550 4125);
WIRE 16 -1 (-2075 4125)(-2550 4125);
WIRE 16 -1 (-2550 4125)(-2550 4075);
WIRE 16 -1 (-2075 4075)(-2550 4075);
WIRE 16 -1 (-2550 4075)(-2550 4025);
WIRE 16 -1 (-2075 4025)(-2550 4025);
WIRE 16 -1 (-2550 4025)(-2550 3975);
WIRE 16 -1 (-2075 3975)(-2550 3975);
WIRE 16 -1 (-2550 3975)(-2550 3925);
WIRE 16 -1 (-2075 3925)(-2550 3925);
WIRE 16 -1 (-2550 3925)(-2550 3875);
WIRE 16 -1 (-2075 3875)(-2550 3875);
WIRE 16 -1 (-2550 3875)(-2550 3825);
WIRE 16 -1 (-2075 3825)(-2550 3825);
WIRE 16 -1 (-2550 3825)(-2550 3775);
WIRE 16 -1 (-2075 3775)(-2550 3775);
WIRE 16 -1 (-2550 3775)(-2550 3725);
WIRE 16 -1 (-2075 3725)(-2550 3725);
WIRE 16 -1 (-2550 3725)(-2550 3675);
WIRE 16 -1 (-2075 3675)(-2550 3675);
WIRE 16 -1 (-2550 3675)(-2550 3625);
WIRE 16 -1 (-2075 3625)(-2550 3625);
WIRE 16 -1 (-2550 3625)(-2550 3575);
WIRE 16 -1 (-2075 3575)(-2550 3575);
WIRE 16 -1 (-2550 3575)(-2550 3525);
WIRE 16 -1 (-2075 3525)(-2550 3525);
WIRE 16 -1 (-2550 3525)(-2550 3475);
WIRE 16 -1 (-2075 3475)(-2550 3475);
WIRE 16 -1 (-2550 3475)(-2550 3425);
WIRE 16 -1 (-2075 3425)(-2550 3425);
WIRE 16 -1 (-2550 3425)(-2550 3375);
WIRE 16 -1 (-2075 3375)(-2550 3375);
WIRE 16 -1 (-2550 3375)(-2550 3325);
WIRE 16 -1 (-2075 3325)(-2550 3325);
WIRE 16 -1 (-2550 3325)(-2550 3275);
WIRE 16 -1 (-2075 3275)(-2550 3275);
WIRE 16 -1 (-2550 3275)(-2550 3225);
WIRE 16 -1 (-2075 3225)(-2550 3225);
WIRE 16 -1 (-2550 3225)(-2550 3175);
WIRE 16 -1 (-2075 3175)(-2550 3175);
WIRE 16 -1 (-2550 3175)(-2550 3125);
WIRE 16 -1 (-2075 3125)(-2550 3125);
WIRE 16 -1 (-2550 3125)(-2550 3075);
WIRE 16 -1 (-2075 3075)(-2550 3075);
WIRE 16 -1 (-2550 3075)(-2550 3025);
WIRE 16 -1 (-2075 3025)(-2550 3025);
WIRE 16 -1 (-2550 3025)(-2550 2975);
WIRE 16 -1 (-2075 2975)(-2550 2975);
WIRE 16 -1 (-2550 2975)(-2550 2925);
WIRE 16 -1 (-2075 2925)(-2550 2925);
WIRE 16 -1 (-2550 2925)(-2550 2875);
WIRE 16 -1 (-2075 2875)(-2550 2875);
WIRE 16 -1 (-2550 2875)(-2550 2825);
WIRE 16 -1 (-2075 2825)(-2550 2825);
WIRE 16 -1 (-2550 2825)(-2550 2775);
WIRE 16 -1 (-2075 2775)(-2550 2775);
WIRE 16 -1 (-2550 2775)(-2550 2725);
WIRE 16 -1 (-2075 2725)(-2550 2725);
WIRE 16 -1 (-2550 2725)(-2550 2675);
WIRE 16 -1 (-2075 2675)(-2550 2675);
WIRE 16 -1 (-2550 2675)(-2550 2625);
WIRE 16 -1 (-2075 2625)(-2550 2625);
WIRE 16 -1 (-2550 2625)(-2550 2575);
WIRE 16 -1 (-2075 2575)(-2550 2575);
WIRE 16 -1 (-2550 2575)(-2550 2525);
WIRE 16 -1 (-2075 2525)(-2550 2525);
WIRE 16 -1 (-2550 2525)(-2550 2475);
WIRE 16 -1 (-2075 2475)(-2550 2475);
WIRE 16 -1 (-2550 2475)(-2550 2425);
WIRE 16 -1 (-2075 2425)(-2550 2425);
WIRE 16 -1 (-2550 2425)(-2550 2375);
WIRE 16 -1 (-2075 2375)(-2550 2375);
WIRE 16 -1 (-2550 2375)(-2550 2325);
WIRE 16 -1 (-2075 2325)(-2550 2325);
WIRE 16 -1 (-2550 2325)(-2550 2275);
WIRE 16 -1 (-2075 2275)(-2550 2275);
WIRE 16 -1 (-2550 2275)(-2550 2225);
WIRE 16 -1 (-2075 2225)(-2550 2225);
WIRE 16 -1 (-2550 2225)(-2550 2175);
WIRE 16 -1 (-2075 2175)(-2550 2175);
WIRE 16 -1 (-2550 2175)(-2550 2125);
WIRE 16 -1 (-2075 2125)(-2550 2125);
WIRE 16 -1 (-2550 2125)(-2550 2075);
WIRE 16 -1 (-2075 2075)(-2550 2075);
WIRE 16 -1 (-2550 2075)(-2550 2025);
WIRE 16 -1 (-2075 2025)(-2550 2025);
WIRE 16 -1 (-2550 2025)(-2550 1975);
WIRE 16 -1 (-2075 1975)(-2550 1975);
WIRE 16 -1 (-2550 1975)(-2550 1925);
WIRE 16 -1 (-2075 1925)(-2550 1925);
WIRE 16 -1 (-2550 1925)(-2550 1875);
WIRE 16 -1 (-2075 1875)(-2550 1875);
WIRE 16 -1 (-2550 1875)(-2550 1825);
WIRE 16 -1 (-2075 1825)(-2550 1825);
WIRE 16 -1 (-2550 1825)(-2550 1775);
WIRE 16 -1 (-2075 1775)(-2550 1775);
WIRE 16 -1 (-2550 1775)(-2550 1725);
WIRE 16 -1 (-2075 1725)(-2550 1725);
WIRE 16 -1 (-2550 1725)(-2550 1675);
WIRE 16 -1 (-2075 1675)(-2550 1675);
WIRE 16 -1 (-2550 1675)(-2550 1625);
WIRE 16 -1 (-2075 1625)(-2550 1625);
WIRE 16 -1 (-2550 1625)(-2550 1575);
WIRE 16 -1 (-2075 1575)(-2550 1575);
WIRE 16 -1 (-2550 1575)(-2550 1525);
WIRE 16 -1 (-2075 1525)(-2550 1525);
WIRE 16 -1 (-2550 1525)(-2550 1475);
WIRE 16 -1 (-2075 1475)(-2550 1475);
WIRE 16 -1 (-2550 1475)(-2550 1425);
WIRE 16 -1 (-2075 1425)(-2550 1425);
WIRE 16 -1 (-2550 1425)(-2550 1375);
WIRE 16 -1 (-2075 1375)(-2550 1375);
WIRE 16 -1 (-2550 1375)(-2550 1325);
WIRE 16 -1 (-2075 1325)(-2550 1325);
WIRE 16 -1 (-2550 1325)(-2550 1275);
WIRE 16 -1 (-2075 1275)(-2550 1275);
WIRE 16 -1 (-2550 1275)(-2550 1225);
WIRE 16 -1 (-2075 1225)(-2550 1225);
WIRE 16 -1 (-2550 1225)(-2550 1175);
WIRE 16 -1 (-2075 1175)(-2550 1175);
WIRE 16 -1 (-2550 1175)(-2550 1125);
WIRE 16 -1 (-2075 1125)(-2550 1125);
WIRE 16 -1 (-2550 1125)(-2550 1075);
WIRE 16 -1 (-2075 1075)(-2550 1075);
WIRE 16 -1 (-2550 1075)(-2550 1025);
WIRE 16 -1 (-2550 1025)(-2075 1025);
WIRE 16 -1 (-2550 1025)(-2550 975);
WIRE 16 -1 (-2550 975)(-2075 975);
WIRE 16 -1 (-2550 675)(-2550 975);
DOT 1 (-4950 1700);
DOT 1 (-4950 950);
DOT 1 (-4950 1050);
DOT 1 (-4950 1100);
DOT 1 (-4950 1150);
DOT 1 (-4950 1200);
DOT 1 (-4950 1300);
DOT 1 (-4950 1350);
DOT 1 (-4950 1450);
DOT 1 (-4950 1400);
DOT 1 (-4950 1500);
DOT 1 (-4950 1550);
DOT 1 (-4950 1600);
DOT 1 (-4950 1650);
DOT 1 (-4950 1750);
DOT 1 (-4950 1800);
DOT 1 (-4950 1850);
DOT 1 (-4950 1950);
DOT 1 (-4950 1900);
DOT 1 (-4950 2000);
DOT 1 (-4950 2100);
DOT 1 (-4950 2150);
DOT 1 (-4950 2200);
DOT 1 (-4950 2250);
DOT 1 (-4950 2300);
DOT 1 (-4950 2350);
DOT 1 (-4950 2400);
DOT 1 (-4950 2450);
DOT 1 (-4950 2500);
DOT 1 (-4950 2600);
DOT 1 (-4950 2550);
DOT 1 (-4950 2650);
DOT 1 (-4950 2700);
DOT 1 (-4950 2750);
DOT 1 (-4950 2850);
DOT 1 (-4950 2800);
DOT 1 (-4950 2900);
DOT 1 (-4950 3000);
DOT 1 (-4950 3100);
DOT 1 (-4950 3050);
DOT 1 (-4950 3150);
DOT 1 (-4950 3200);
DOT 1 (-4950 3250);
DOT 1 (-4950 3400);
DOT 1 (-4950 3300);
DOT 1 (-4950 3350);
DOT 1 (-4950 3500);
DOT 1 (-4950 3450);
DOT 1 (-4950 3550);
DOT 1 (-4950 3600);
DOT 1 (-4950 3650);
DOT 1 (-4950 3700);
DOT 1 (-4950 3800);
DOT 1 (-4950 3850);
DOT 1 (-4950 3900);
DOT 1 (-4950 4000);
DOT 1 (-4950 3950);
DOT 1 (-4950 4050);
DOT 1 (-4950 4100);
DOT 1 (-4950 4150);
DOT 1 (-4950 4250);
DOT 1 (-4950 4200);
DOT 1 (-4950 4300);
DOT 1 (-4950 4350);
DOT 1 (-3125 950);
DOT 1 (-3125 1050);
DOT 1 (-3125 1000);
DOT 1 (-3125 1100);
DOT 1 (-3125 1150);
DOT 1 (-3125 1200);
DOT 1 (-3125 1250);
DOT 1 (-3125 1300);
DOT 1 (-3125 1350);
DOT 1 (-3125 1450);
DOT 1 (-3125 1400);
DOT 1 (-3125 1500);
DOT 1 (-3125 1550);
DOT 1 (-3125 1600);
DOT 1 (-3125 1700);
DOT 1 (-3125 1650);
DOT 1 (-3125 1800);
DOT 1 (-3125 1750);
DOT 1 (-3125 1850);
DOT 1 (-3125 1950);
DOT 1 (-3125 2000);
DOT 1 (-3125 2050);
DOT 1 (-3125 2100);
DOT 1 (-3125 2150);
DOT 1 (-3125 2200);
DOT 1 (-3125 2250);
DOT 1 (-3125 2350);
DOT 1 (-3125 2400);
DOT 1 (-3125 2450);
DOT 1 (-3125 2500);
DOT 1 (-3125 2600);
DOT 1 (-3125 2650);
DOT 1 (-3125 2700);
DOT 1 (-3125 2750);
DOT 1 (-3125 2850);
DOT 1 (-3125 2800);
DOT 1 (-3125 2900);
DOT 1 (-3125 2950);
DOT 1 (-3125 3000);
DOT 1 (-3125 3100);
DOT 1 (-3125 3050);
DOT 1 (-3125 3150);
DOT 1 (-3125 3200);
DOT 1 (-3125 3250);
DOT 1 (-3125 3300);
DOT 1 (-3125 3400);
DOT 1 (-3125 3350);
DOT 1 (-3125 3500);
DOT 1 (-3125 3450);
DOT 1 (-3125 3550);
DOT 1 (-3125 3600);
DOT 1 (-3125 3650);
DOT 1 (-3125 3750);
DOT 1 (-3125 3700);
DOT 1 (-3125 3800);
DOT 1 (-3125 3850);
DOT 1 (-3125 3900);
DOT 1 (-3125 4000);
DOT 1 (-3125 3950);
DOT 1 (-3125 4050);
DOT 1 (-3125 4100);
DOT 1 (-3125 4150);
DOT 1 (-3125 4250);
DOT 1 (-3125 4200);
DOT 1 (-3125 4300);
DOT 1 (-3125 4350);
DOT 1 (-2550 3925);
DOT 1 (-2550 1775);
DOT 1 (-2550 975);
DOT 1 (-2550 1025);
DOT 1 (-2550 1075);
DOT 1 (-2550 1175);
DOT 1 (-2550 1125);
DOT 1 (-2550 1225);
DOT 1 (-2550 1275);
DOT 1 (-2550 1325);
DOT 1 (-2550 1425);
DOT 1 (-2550 1375);
DOT 1 (-2550 1475);
DOT 1 (-2550 1525);
DOT 1 (-2550 1575);
DOT 1 (-2550 1625);
DOT 1 (-2550 1675);
DOT 1 (-2550 1925);
DOT 1 (-2550 1975);
DOT 1 (-2550 2075);
DOT 1 (-2550 2025);
DOT 1 (-2550 2125);
DOT 1 (-2550 2175);
DOT 1 (-2550 2225);
DOT 1 (-2550 2275);
DOT 1 (-2550 2325);
DOT 1 (-2550 2375);
DOT 1 (-2550 2425);
DOT 1 (-2550 2475);
DOT 1 (-2550 2575);
DOT 1 (-2550 2525);
DOT 1 (-2550 2625);
DOT 1 (-2550 2725);
DOT 1 (-2550 2775);
DOT 1 (-2550 2825);
DOT 1 (-2550 2875);
DOT 1 (-2550 2975);
DOT 1 (-2550 2925);
DOT 1 (-2550 3025);
DOT 1 (-2550 3075);
DOT 1 (-2550 3125);
DOT 1 (-2550 3225);
DOT 1 (-2550 3175);
DOT 1 (-2550 3275);
DOT 1 (-2550 3325);
DOT 1 (-2550 3375);
DOT 1 (-2550 3425);
DOT 1 (-2550 3475);
DOT 1 (-2550 3525);
DOT 1 (-2550 3575);
DOT 1 (-2550 3625);
DOT 1 (-2550 3775);
DOT 1 (-2550 3675);
DOT 1 (-2550 3725);
DOT 1 (-2550 3825);
DOT 1 (-2550 3875);
DOT 1 (-2550 3975);
DOT 1 (-2550 4025);
DOT 1 (-2550 4125);
DOT 1 (-2550 4075);
DOT 1 (-2550 4175);
DOT 1 (-2550 4225);
DOT 1 (-2550 4275);
DOT 1 (-2550 4325);
DOT 1 (-2550 4375);
DOT 1 (-400 975);
DOT 1 (-400 1075);
DOT 1 (-400 1025);
DOT 1 (-400 1275);
DOT 1 (-400 1225);
DOT 1 (-400 1175);
DOT 1 (-400 1125);
DOT 1 (-400 1325);
DOT 1 (-400 1575);
DOT 1 (-400 1475);
DOT 1 (-400 1425);
DOT 1 (-400 1375);
DOT 1 (-400 1525);
DOT 1 (-400 1625);
DOT 1 (-400 1925);
DOT 1 (-400 1875);
DOT 1 (-400 2175);
DOT 1 (-400 2125);
DOT 1 (-400 2375);
DOT 1 (-400 2575);
DOT 1 (-400 2725);
DOT 1 (-400 2825);
DOT 1 (-400 2875);
DOT 1 (-400 3075);
DOT 1 (-400 3025);
DOT 1 (-400 2975);
DOT 1 (-400 2925);
DOT 1 (-400 3125);
DOT 1 (-400 3325);
DOT 1 (-400 3275);
DOT 1 (-400 3225);
DOT 1 (-400 3175);
DOT 1 (-400 3375);
DOT 1 (-400 3575);
DOT 1 (-400 3525);
DOT 1 (-400 3475);
DOT 1 (-400 3425);
DOT 1 (-400 3625);
DOT 1 (-400 3825);
DOT 1 (-400 3775);
DOT 1 (-400 3725);
DOT 1 (-400 3675);
DOT 1 (-400 3875);
DOT 1 (-400 4125);
DOT 1 (-400 4025);
DOT 1 (-400 3975);
DOT 1 (-400 3925);
DOT 1 (-400 4075);
DOT 1 (-400 4325);
DOT 1 (-400 4275);
DOT 1 (-400 4225);
DOT 1 (-400 4175);
DOT 1 (-400 4375);
DOT 1 (225 3150);
DOT 1 (225 950);
DOT 1 (225 1000);
DOT 1 (225 1100);
DOT 1 (225 1050);
DOT 1 (225 1150);
DOT 1 (225 1200);
DOT 1 (225 1250);
DOT 1 (225 1300);
DOT 1 (225 1350);
DOT 1 (225 1400);
DOT 1 (225 1450);
DOT 1 (225 1550);
DOT 1 (225 1600);
DOT 1 (225 1650);
DOT 1 (225 1750);
DOT 1 (225 1700);
DOT 1 (225 1800);
DOT 1 (225 1850);
DOT 1 (225 1900);
DOT 1 (225 2000);
DOT 1 (225 1950);
DOT 1 (225 2050);
DOT 1 (225 2100);
DOT 1 (225 2150);
DOT 1 (225 2200);
DOT 1 (225 2250);
DOT 1 (225 2300);
DOT 1 (225 2400);
DOT 1 (225 2350);
DOT 1 (225 2450);
DOT 1 (225 2500);
DOT 1 (225 2550);
DOT 1 (225 2650);
DOT 1 (225 2600);
DOT 1 (225 2700);
DOT 1 (225 2800);
DOT 1 (225 2900);
DOT 1 (225 2850);
DOT 1 (225 2950);
DOT 1 (225 3000);
DOT 1 (225 3050);
DOT 1 (225 3100);
DOT 1 (225 3200);
DOT 1 (225 3250);
DOT 1 (225 3300);
DOT 1 (225 3350);
DOT 1 (225 3400);
DOT 1 (225 3450);
DOT 1 (225 3550);
DOT 1 (225 3500);
DOT 1 (225 3600);
DOT 1 (225 3650);
DOT 1 (225 3700);
DOT 1 (225 3800);
DOT 1 (225 3750);
DOT 1 (225 3850);
DOT 1 (225 3900);
DOT 1 (225 3950);
DOT 1 (225 4050);
DOT 1 (225 4000);
DOT 1 (225 4100);
DOT 1 (225 4150);
DOT 1 (225 4200);
DOT 1 (225 4300);
DOT 1 (225 4250);
DOT 1 (225 4350);
DOT 1 (2200 4350);
DOT 1 (2200 4300);
DOT 1 (225 2750);
DOT 1 (-400 2325);
DOT 1 (-3125 2550);
DOT 1 (-3125 2300);
DOT 1 (-2550 2675);
DOT 1 (-4950 2950);
DOT 1 (2200 4250);
DOT 1 (2200 4200);
DOT 1 (225 1500);
DOT 1 (-400 1675);
DOT 1 (-400 1725);
DOT 1 (-400 1775);
DOT 1 (-400 1825);
DOT 1 (-400 1975);
DOT 1 (-400 2025);
DOT 1 (-400 2075);
DOT 1 (-400 2225);
DOT 1 (-400 2275);
DOT 1 (-400 2425);
DOT 1 (-400 2475);
DOT 1 (-400 2525);
DOT 1 (-400 2625);
DOT 1 (-400 2675);
DOT 1 (-400 2775);
DOT 1 (-2550 1875);
DOT 1 (-4950 2050);
DOT 1 (-2550 1725);
DOT 1 (-2550 1825);
DOT 1 (-4950 3750);
DOT 1 (-4950 1000);
DOT 1 (-4950 1250);
DOT 1 (-3125 1900);
FORCENOTE
ROOM=SB
(-5300 225) 0;
DISPLAY LEFT (-5300 225);
DISPLAY 1.021277 (-5300 225);
PAINT PURPLE (-5300 225);
QUIT
